FILE_TYPE = MACRO_DRAWING;
SET COLOR_WIRE YELLOW;
SET COLOR_PROP ORANGE;
SET COLOR_DOT WHITE;
SET COLOR_ARC YELLOW;
SET COLOR_BODY GREEN;
SET COLOR_NOTE PURPLE;
SET PROP_DISPLAY VALUE;
SET PAGE_NUMBER P183;
FORCEADD OFFPAGE..1
(-7175 3875);
FORCEPROP 2 LAST $XR0 183 
J 0
(-7427 3875);
DISPLAY 0.638298 (-7427 3875);
PAINT MONO (-7427 3875);
FORCEPROP 1 LAST OFFPAGE TRUE
J 0
(-6850 3750);
DISPLAY 0.872340 (-6850 3750);
PAINT GREEN (-6850 3750);
DISPLAY INVISIBLE (-6850 3750);
FORCEPROP 1 LAST COMMENT_BODY TRUE
J 0
(-7050 3775);
DISPLAY 0.872340 (-7050 3775);
PAINT GREEN (-7050 3775);
DISPLAY INVISIBLE (-7050 3775);
FORCEPROP 2 LAST PATH I1
J 0
(-7125 3950);
DISPLAY 1.021277 (-7125 3950);
DISPLAY INVISIBLE (-7125 3950);
FORCEPROP 2 LAST CDS_LIB standard
J 2
(-7175 3875);
DISPLAY INVISIBLE (-7175 3875);
FORCEADD OFFPAGE..2
R 2
(-7225 4475);
FORCEPROP 2 LAST $XR0 183 
J 0
(-7480 4475);
DISPLAY 0.638298 (-7480 4475);
PAINT MONO (-7480 4475);
FORCEPROP 2 LAST PATH I10
J 0
(-7175 4550);
DISPLAY 1.021277 (-7175 4550);
DISPLAY INVISIBLE (-7175 4550);
FORCEPROP 1 LAST COMMENT_BODY TRUE
J 2
(-7180 4380);
DISPLAY 0.872340 (-7180 4380);
PAINT GREEN (-7180 4380);
DISPLAY INVISIBLE (-7180 4380);
FORCEPROP 2 LAST CDS_LIB standard
J 2
(-7225 4475);
DISPLAY INVISIBLE (-7225 4475);
FORCEPROP 1 LAST OFFPAGE TRUE
J 2
(-7550 4350);
DISPLAY 0.872340 (-7550 4350);
PAINT GREEN (-7550 4350);
DISPLAY INVISIBLE (-7550 4350);
FORCEADD Q_INDUCTOR..1
(-3300 4500);
FORCEPROP 1 LAST LOCATION PL23
J 0
(-3325 4550);
DISPLAY 0.489362 (-3325 4550);
PAINT SKYBLUE (-3325 4550);
FORCEPROP 0 LAST $SEC 1
J 0
(-3325 4575);
DISPLAY 0.680851 (-3325 4575);
PAINT MONO (-3325 4575);
DISPLAY INVISIBLE (-3325 4575);
FORCEPROP 0 LAST CDS_SEC 1
J 0
(-3325 4575);
DISPLAY 1.021277 (-3325 4575);
DISPLAY INVISIBLE (-3325 4575);
FORCEPROP 0 LASTPIN (-3400 4475) $PN 1
J 2
(-3410 4485);
DISPLAY 0.489362 (-3410 4485);
PAINT MONO (-3410 4485);
FORCEPROP 0 LASTPIN (-3200 4475) $PN 2
J 0
(-3190 4485);
DISPLAY 0.489362 (-3190 4485);
PAINT MONO (-3190 4485);
FORCEPROP 1 LAST MATERIAL IND
J 0
(-3400 4325);
DISPLAY 0.489362 (-3400 4325);
PAINT SKYBLUE (-3400 4325);
FORCEPROP 2 LAST VALUE 90NH/155AA
J 0
(-3400 4425);
DISPLAY 0.489362 (-3400 4425);
PAINT SKYBLUE (-3400 4425);
FORCEPROP 1 LAST PART_NUMBER CVA90^0KZ04
J 0
(-3400 4375);
DISPLAY 0.489362 (-3400 4375);
PAINT SKYBLUE (-3400 4375);
FORCEPROP 2 LAST PACK_TYPE SMLF
J 0
(-3400 4275);
DISPLAY 0.489362 (-3400 4275);
PAINT SKYBLUE (-3400 4275);
FORCEPROP 2 LAST CDS_LIB pure_quanta
J 0
(-3300 4500);
DISPLAY INVISIBLE (-3300 4500);
FORCEPROP 1 LAST NEEDS_NO_SIZE TRUE
J 0
(-3300 4500);
DISPLAY 0.468085 (-3300 4500);
PAINT GREEN (-3300 4500);
DISPLAY INVISIBLE (-3300 4500);
FORCEPROP 1 LAST PATH I101
J 0
(-3225 4555);
DISPLAY 0.723404 (-3225 4555);
PAINT GREEN (-3225 4555);
DISPLAY INVISIBLE (-3225 4555);
FORCEADD VCC_CORE..1
(-3925 5725);
FORCEPROP 3 LASTPIN (-3925 5675) SIG_NAME SW_P12V_STBY_PVDD11_S3_P0_FLT\g
J 0
(-3915 5685);
DISPLAY 0.659574 (-3915 5685);
PAINT MONO (-3915 5685);
DISPLAY INVISIBLE (-3915 5685);
FORCEPROP 1 LAST HDL_POWER SW_P12V_STBY_PVDD11_S3_P0_FLT
J 1
(-3925 5775);
DISPLAY 0.489362 (-3925 5775);
PAINT GREEN (-3925 5775);
FORCEPROP 2 LAST CDS_LIB pure_quanta_power
J 0
(-3925 5725);
DISPLAY INVISIBLE (-3925 5725);
FORCEPROP 1 LAST PATH I104
J 0
(-3875 5750);
DISPLAY 0.872340 (-3875 5750);
PAINT AQUA (-3875 5750);
DISPLAY INVISIBLE (-3875 5750);
FORCEADD Q_INDUCTOR..1
(-3400 1575);
FORCEPROP 1 LAST LOCATION PL22
J 0
(-3425 1625);
DISPLAY 0.489362 (-3425 1625);
PAINT SKYBLUE (-3425 1625);
FORCEPROP 0 LAST $SEC 1
J 0
(-3425 1650);
DISPLAY 0.680851 (-3425 1650);
PAINT MONO (-3425 1650);
DISPLAY INVISIBLE (-3425 1650);
FORCEPROP 0 LAST CDS_SEC 1
J 0
(-3425 1650);
DISPLAY 1.021277 (-3425 1650);
DISPLAY INVISIBLE (-3425 1650);
FORCEPROP 0 LASTPIN (-3500 1550) $PN 1
J 2
(-3510 1560);
DISPLAY 0.489362 (-3510 1560);
PAINT MONO (-3510 1560);
FORCEPROP 0 LASTPIN (-3300 1550) $PN 2
J 0
(-3290 1560);
DISPLAY 0.489362 (-3290 1560);
PAINT MONO (-3290 1560);
FORCEPROP 1 LAST MATERIAL IND
J 0
(-3500 1400);
DISPLAY 0.489362 (-3500 1400);
PAINT SKYBLUE (-3500 1400);
FORCEPROP 2 LAST VALUE 90NH/155AA
J 0
(-3500 1500);
DISPLAY 0.489362 (-3500 1500);
PAINT SKYBLUE (-3500 1500);
FORCEPROP 1 LAST PART_NUMBER CVA90^0KZ04
J 0
(-3500 1450);
DISPLAY 0.489362 (-3500 1450);
PAINT SKYBLUE (-3500 1450);
FORCEPROP 2 LAST PACK_TYPE SMLF
J 0
(-3500 1350);
DISPLAY 0.489362 (-3500 1350);
PAINT SKYBLUE (-3500 1350);
FORCEPROP 1 LAST NEEDS_NO_SIZE TRUE
J 0
(-3400 1575);
DISPLAY 0.468085 (-3400 1575);
PAINT GREEN (-3400 1575);
DISPLAY INVISIBLE (-3400 1575);
FORCEPROP 2 LAST CDS_LIB pure_quanta
J 0
(-3400 1575);
DISPLAY INVISIBLE (-3400 1575);
FORCEPROP 1 LAST PATH I105
J 0
(-3325 1630);
DISPLAY 0.723404 (-3325 1630);
PAINT GREEN (-3325 1630);
DISPLAY INVISIBLE (-3325 1630);
FORCEADD Q_CAP..1
(-4075 2450);
FORCEPROP 1 LAST LOCATION PC216_2
J 0
(-4025 2550);
DISPLAY 0.489362 (-4025 2550);
PAINT SKYBLUE (-4025 2550);
FORCEPROP 0 LAST $SEC 1
J 0
(-4025 2575);
DISPLAY 0.680851 (-4025 2575);
PAINT MONO (-4025 2575);
DISPLAY INVISIBLE (-4025 2575);
FORCEPROP 0 LAST CDS_SEC 1
J 0
(-4025 2575);
DISPLAY 1.021277 (-4025 2575);
DISPLAY INVISIBLE (-4025 2575);
FORCEPROP 1 LASTPIN (-4075 2550) $PN 1
J 0
(-4065 2530);
DISPLAY 0.489362 (-4065 2530);
PAINT MONO (-4065 2530);
FORCEPROP 1 LASTPIN (-4075 2350) $PN 2
J 0
(-4065 2330);
DISPLAY 0.489362 (-4065 2330);
PAINT MONO (-4065 2330);
FORCEPROP 1 LAST MATERIAL X6S
J 0
(-4025 2350);
DISPLAY 0.489362 (-4025 2350);
PAINT SKYBLUE (-4025 2350);
FORCEPROP 1 LAST TOLERANCE 10%
J 0
(-4025 2400);
DISPLAY 0.489362 (-4025 2400);
PAINT SKYBLUE (-4025 2400);
FORCEPROP 1 LAST VALUE 10UF
J 0
(-4025 2500);
DISPLAY 0.489362 (-4025 2500);
PAINT SKYBLUE (-4025 2500);
FORCEPROP 1 LAST PART_NUMBER CH6104KEA00
J 0
(-4025 2300);
DISPLAY 0.489362 (-4025 2300);
PAINT SKYBLUE (-4025 2300);
FORCEPROP 1 LAST VOLTAGE 25V
J 0
(-4025 2450);
DISPLAY 0.489362 (-4025 2450);
PAINT SKYBLUE (-4025 2450);
FORCEPROP 1 LAST PACK_TYPE C0805
J 0
(-4025 2250);
DISPLAY 0.489362 (-4025 2250);
PAINT SKYBLUE (-4025 2250);
FORCEPROP 2 LAST CDS_LIB pure_quanta
J 0
(-4075 2450);
DISPLAY INVISIBLE (-4075 2450);
FORCEPROP 1 LAST PATH I107
J 0
(-4025 2600);
DISPLAY 0.978723 (-4025 2600);
PAINT WHITE (-4025 2600);
DISPLAY INVISIBLE (-4025 2600);
FORCEADD Q_RES..1
(-3800 3500);
FORCEPROP 1 LAST LOCATION PR137
J 0
(-3850 3550);
DISPLAY 0.489362 (-3850 3550);
PAINT SKYBLUE (-3850 3550);
FORCEPROP 0 LAST $SEC 1
J 0
(-3850 3600);
DISPLAY 0.680851 (-3850 3600);
PAINT MONO (-3850 3600);
DISPLAY INVISIBLE (-3850 3600);
FORCEPROP 0 LAST CDS_SEC 1
J 0
(-3850 3600);
DISPLAY 1.021277 (-3850 3600);
DISPLAY INVISIBLE (-3850 3600);
FORCEPROP 1 LASTPIN (-3900 3500) $PN 1
J 0
(-3888 3512);
DISPLAY 0.489362 (-3888 3512);
PAINT MONO (-3888 3512);
FORCEPROP 1 LASTPIN (-3700 3500) $PN 2
J 0
(-3738 3512);
DISPLAY 0.489362 (-3738 3512);
PAINT MONO (-3738 3512);
FORCEPROP 1 LAST WATTAGE 1/16W
J 0
(-3700 3450);
DISPLAY 0.489362 (-3700 3450);
PAINT SKYBLUE (-3700 3450);
FORCEPROP 1 LAST MATERIAL CHIP
J 0
(-4050 3425);
DISPLAY 0.489362 (-4050 3425);
PAINT SKYBLUE (-4050 3425);
FORCEPROP 1 LAST TOLERANCE 5%
J 0
(-3675 3525);
DISPLAY 0.489362 (-3675 3525);
PAINT SKYBLUE (-3675 3525);
FORCEPROP 1 LAST VALUE 0
J 2
(-3925 3525);
DISPLAY 0.489362 (-3925 3525);
PAINT SKYBLUE (-3925 3525);
FORCEPROP 1 LAST PART_NUMBER CS00002JB38
J 0
(-4050 3450);
DISPLAY 0.489362 (-4050 3450);
PAINT SKYBLUE (-4050 3450);
FORCEPROP 1 LAST PACK_TYPE 0402LF
J 0
(-3700 3425);
DISPLAY 0.489362 (-3700 3425);
PAINT SKYBLUE (-3700 3425);
FORCEPROP 2 LAST CDS_LIB pure_quanta
J 0
(-3800 3500);
DISPLAY INVISIBLE (-3800 3500);
FORCEPROP 1 LAST PATH I110
J 0
(-3850 3650);
DISPLAY 0.978723 (-3850 3650);
PAINT WHITE (-3850 3650);
DISPLAY INVISIBLE (-3850 3650);
FORCEADD Q_RES..1
(-3475 600);
FORCEPROP 1 LAST LOCATION PR138
J 0
(-3525 650);
DISPLAY 0.489362 (-3525 650);
PAINT SKYBLUE (-3525 650);
FORCEPROP 0 LAST $SEC 1
J 0
(-3525 700);
DISPLAY 0.680851 (-3525 700);
PAINT MONO (-3525 700);
DISPLAY INVISIBLE (-3525 700);
FORCEPROP 0 LAST CDS_SEC 1
J 0
(-3525 700);
DISPLAY 1.021277 (-3525 700);
DISPLAY INVISIBLE (-3525 700);
FORCEPROP 1 LASTPIN (-3575 600) $PN 1
J 0
(-3563 612);
DISPLAY 0.489362 (-3563 612);
PAINT MONO (-3563 612);
FORCEPROP 1 LASTPIN (-3375 600) $PN 2
J 0
(-3413 612);
DISPLAY 0.489362 (-3413 612);
PAINT MONO (-3413 612);
FORCEPROP 1 LAST WATTAGE 1/16W
J 0
(-3375 550);
DISPLAY 0.489362 (-3375 550);
PAINT SKYBLUE (-3375 550);
FORCEPROP 1 LAST MATERIAL CHIP
J 0
(-3725 525);
DISPLAY 0.489362 (-3725 525);
PAINT SKYBLUE (-3725 525);
FORCEPROP 1 LAST TOLERANCE 5%
J 0
(-3350 625);
DISPLAY 0.489362 (-3350 625);
PAINT SKYBLUE (-3350 625);
FORCEPROP 1 LAST VALUE 0
J 2
(-3600 625);
DISPLAY 0.489362 (-3600 625);
PAINT SKYBLUE (-3600 625);
FORCEPROP 1 LAST PART_NUMBER CS00002JB38
J 0
(-3725 550);
DISPLAY 0.489362 (-3725 550);
PAINT SKYBLUE (-3725 550);
FORCEPROP 1 LAST PACK_TYPE 0402LF
J 0
(-3375 525);
DISPLAY 0.489362 (-3375 525);
PAINT SKYBLUE (-3375 525);
FORCEPROP 2 LAST CDS_LIB pure_quanta
J 0
(-3475 600);
DISPLAY INVISIBLE (-3475 600);
FORCEPROP 1 LAST PATH I111
J 0
(-3525 750);
DISPLAY 0.978723 (-3525 750);
PAINT WHITE (-3525 750);
DISPLAY INVISIBLE (-3525 750);
FORCEADD Q_CAPP..1
(-2425 2900);
FORCEPROP 1 LAST LOCATION PC226
J 0
(-2375 3000);
DISPLAY 0.489362 (-2375 3000);
PAINT SKYBLUE (-2375 3000);
FORCEPROP 0 LAST $SEC 1
J 0
(-2375 3050);
DISPLAY 0.680851 (-2375 3050);
PAINT MONO (-2375 3050);
DISPLAY INVISIBLE (-2375 3050);
FORCEPROP 0 LAST CDS_SEC 1
J 0
(-2375 3050);
DISPLAY 1.021277 (-2375 3050);
DISPLAY INVISIBLE (-2375 3050);
FORCEPROP 1 LASTPIN (-2425 3000) $PN 1
J 0
(-2415 2985);
DISPLAY 0.489362 (-2415 2985);
PAINT MONO (-2415 2985);
FORCEPROP 1 LASTPIN (-2425 2800) $PN 2
J 0
(-2415 2785);
DISPLAY 0.489362 (-2415 2785);
PAINT MONO (-2415 2785);
FORCEPROP 1 LAST MATERIAL SPCAP
J 0
(-2375 2800);
DISPLAY 0.489362 (-2375 2800);
PAINT SKYBLUE (-2375 2800);
FORCEPROP 1 LAST TOLERANCE 20%
J 0
(-2375 2900);
DISPLAY 0.489362 (-2375 2900);
PAINT SKYBLUE (-2375 2900);
FORCEPROP 1 LAST VALUE 470UF
J 0
(-2375 2950);
DISPLAY 0.489362 (-2375 2950);
PAINT SKYBLUE (-2375 2950);
FORCEPROP 1 LAST PART_NUMBER CH747LM8825
J 0
(-2375 2700);
DISPLAY 0.489362 (-2375 2700);
PAINT SKYBLUE (-2375 2700);
FORCEPROP 1 LAST VOLTAGE 2.5V
J 0
(-2375 2850);
DISPLAY 0.489362 (-2375 2850);
PAINT SKYBLUE (-2375 2850);
FORCEPROP 1 LAST PACK_TYPE SMLF
J 0
(-2375 2750);
DISPLAY 0.489362 (-2375 2750);
PAINT SKYBLUE (-2375 2750);
FORCEPROP 2 LAST CDS_LIB pure_quanta
J 0
(-2425 2900);
DISPLAY INVISIBLE (-2425 2900);
FORCEPROP 1 LAST PATH I118
J 0
(-2375 3050);
DISPLAY 0.978723 (-2375 3050);
DISPLAY INVISIBLE (-2375 3050);
FORCEADD Q_CAPP..1
(-1700 2925);
FORCEPROP 1 LAST LOCATION PC228
J 0
(-1650 3025);
DISPLAY 0.489362 (-1650 3025);
PAINT SKYBLUE (-1650 3025);
FORCEPROP 0 LAST $SEC 1
J 0
(-1650 3075);
DISPLAY 0.680851 (-1650 3075);
PAINT MONO (-1650 3075);
DISPLAY INVISIBLE (-1650 3075);
FORCEPROP 0 LAST CDS_SEC 1
J 0
(-1650 3075);
DISPLAY 1.021277 (-1650 3075);
DISPLAY INVISIBLE (-1650 3075);
FORCEPROP 1 LASTPIN (-1700 3025) $PN 1
J 0
(-1690 3010);
DISPLAY 0.489362 (-1690 3010);
PAINT MONO (-1690 3010);
FORCEPROP 1 LASTPIN (-1700 2825) $PN 2
J 0
(-1690 2810);
DISPLAY 0.489362 (-1690 2810);
PAINT MONO (-1690 2810);
FORCEPROP 1 LAST MATERIAL OSCON
J 0
(-1650 2825);
DISPLAY 0.489362 (-1650 2825);
PAINT SKYBLUE (-1650 2825);
FORCEPROP 1 LAST PART_NUMBER CC7390JMZ12
J 0
(-1650 2725);
DISPLAY 0.489362 (-1650 2725);
PAINT SKYBLUE (-1650 2725);
FORCEPROP 1 LAST VOLTAGE 2.5V
J 0
(-1650 2875);
DISPLAY 0.489362 (-1650 2875);
PAINT SKYBLUE (-1650 2875);
FORCEPROP 1 LAST PACK_TYPE SMLF
J 0
(-1650 2775);
DISPLAY 0.489362 (-1650 2775);
PAINT SKYBLUE (-1650 2775);
FORCEPROP 1 LAST TOLERANCE 20%
J 0
(-1650 2925);
DISPLAY 0.489362 (-1650 2925);
PAINT SKYBLUE (-1650 2925);
FORCEPROP 1 LAST VALUE 390UF
J 0
(-1650 2975);
DISPLAY 0.489362 (-1650 2975);
PAINT SKYBLUE (-1650 2975);
FORCEPROP 2 LAST CDS_LIB pure_quanta
J 0
(-1700 2925);
DISPLAY INVISIBLE (-1700 2925);
FORCEPROP 1 LAST PATH I119
J 0
(-1650 3075);
DISPLAY 0.978723 (-1650 3075);
DISPLAY INVISIBLE (-1650 3075);
FORCEADD Q_CAPP..1
(-1375 2925);
FORCEPROP 1 LAST LOCATION PC229
J 0
(-1325 3025);
DISPLAY 0.489362 (-1325 3025);
PAINT SKYBLUE (-1325 3025);
FORCEPROP 0 LAST $SEC 1
J 0
(-1325 3075);
DISPLAY 0.680851 (-1325 3075);
PAINT MONO (-1325 3075);
DISPLAY INVISIBLE (-1325 3075);
FORCEPROP 0 LAST CDS_SEC 1
J 0
(-1325 3075);
DISPLAY 1.021277 (-1325 3075);
DISPLAY INVISIBLE (-1325 3075);
FORCEPROP 1 LASTPIN (-1375 3025) $PN 1
J 0
(-1365 3010);
DISPLAY 0.489362 (-1365 3010);
PAINT MONO (-1365 3010);
FORCEPROP 1 LASTPIN (-1375 2825) $PN 2
J 0
(-1365 2810);
DISPLAY 0.489362 (-1365 2810);
PAINT MONO (-1365 2810);
FORCEPROP 1 LAST MATERIAL OSCON
J 0
(-1325 2825);
DISPLAY 0.489362 (-1325 2825);
PAINT SKYBLUE (-1325 2825);
FORCEPROP 1 LAST TOLERANCE 20%
J 0
(-1325 2925);
DISPLAY 0.489362 (-1325 2925);
PAINT SKYBLUE (-1325 2925);
FORCEPROP 1 LAST VALUE 390UF
J 0
(-1325 2975);
DISPLAY 0.489362 (-1325 2975);
PAINT SKYBLUE (-1325 2975);
FORCEPROP 1 LAST PART_NUMBER CC7390JMZ12
J 0
(-1325 2725);
DISPLAY 0.489362 (-1325 2725);
PAINT SKYBLUE (-1325 2725);
FORCEPROP 1 LAST VOLTAGE 2.5V
J 0
(-1325 2875);
DISPLAY 0.489362 (-1325 2875);
PAINT SKYBLUE (-1325 2875);
FORCEPROP 1 LAST PACK_TYPE SMLF
J 0
(-1325 2775);
DISPLAY 0.489362 (-1325 2775);
PAINT SKYBLUE (-1325 2775);
FORCEPROP 2 LAST CDS_LIB pure_quanta
J 0
(-1375 2925);
DISPLAY INVISIBLE (-1375 2925);
FORCEPROP 1 LAST PATH I120
J 0
(-1325 3075);
DISPLAY 0.978723 (-1325 3075);
DISPLAY INVISIBLE (-1325 3075);
FORCEADD Q_CAPP..1
(-1075 2925);
FORCEPROP 1 LAST LOCATION PC230
J 0
(-1025 3025);
DISPLAY 0.489362 (-1025 3025);
PAINT SKYBLUE (-1025 3025);
FORCEPROP 0 LAST $SEC 1
J 0
(-1025 3075);
DISPLAY 0.680851 (-1025 3075);
PAINT MONO (-1025 3075);
DISPLAY INVISIBLE (-1025 3075);
FORCEPROP 0 LAST CDS_SEC 1
J 0
(-1025 3075);
DISPLAY 1.021277 (-1025 3075);
DISPLAY INVISIBLE (-1025 3075);
FORCEPROP 1 LASTPIN (-1075 3025) $PN 1
J 0
(-1065 3010);
DISPLAY 0.489362 (-1065 3010);
PAINT MONO (-1065 3010);
FORCEPROP 1 LASTPIN (-1075 2825) $PN 2
J 0
(-1065 2810);
DISPLAY 0.489362 (-1065 2810);
PAINT MONO (-1065 2810);
FORCEPROP 1 LAST MATERIAL OSCON
J 0
(-1025 2825);
DISPLAY 0.489362 (-1025 2825);
PAINT SKYBLUE (-1025 2825);
FORCEPROP 1 LAST TOLERANCE 20%
J 0
(-1025 2925);
DISPLAY 0.489362 (-1025 2925);
PAINT SKYBLUE (-1025 2925);
FORCEPROP 1 LAST VALUE 390UF
J 0
(-1025 2975);
DISPLAY 0.489362 (-1025 2975);
PAINT SKYBLUE (-1025 2975);
FORCEPROP 1 LAST PART_NUMBER CC7390JMZ12
J 0
(-1025 2725);
DISPLAY 0.489362 (-1025 2725);
PAINT SKYBLUE (-1025 2725);
FORCEPROP 1 LAST VOLTAGE 2.5V
J 0
(-1025 2875);
DISPLAY 0.489362 (-1025 2875);
PAINT SKYBLUE (-1025 2875);
FORCEPROP 1 LAST PACK_TYPE SMLF
J 0
(-1025 2775);
DISPLAY 0.489362 (-1025 2775);
PAINT SKYBLUE (-1025 2775);
FORCEPROP 2 LAST CDS_LIB pure_quanta
J 0
(-1075 2925);
DISPLAY INVISIBLE (-1075 2925);
FORCEPROP 1 LAST PATH I121
J 0
(-1025 3075);
DISPLAY 0.978723 (-1025 3075);
DISPLAY INVISIBLE (-1025 3075);
FORCEADD VCC_CORE..1
(-1700 3150);
FORCEPROP 3 LASTPIN (-1700 3100) SIG_NAME PVDD11_S3_P0\g
J 0
(-1690 3110);
DISPLAY 0.659574 (-1690 3110);
PAINT MONO (-1690 3110);
DISPLAY INVISIBLE (-1690 3110);
FORCEPROP 1 LAST HDL_POWER PVDD11_S3_P0
J 1
(-1700 3200);
DISPLAY 0.489362 (-1700 3200);
PAINT GREEN (-1700 3200);
FORCEPROP 2 LAST CDS_LIB pure_quanta_power
J 0
(-1700 3150);
DISPLAY INVISIBLE (-1700 3150);
FORCEPROP 1 LAST PATH I122
J 0
(-1650 3175);
DISPLAY 0.872340 (-1650 3175);
PAINT AQUA (-1650 3175);
DISPLAY INVISIBLE (-1650 3175);
FORCEADD UNIVERSAL_GND..1
(-1700 2600);
FORCEPROP 3 LASTPIN (-1700 2650) SIG_NAME GND\g
J 0
(-1690 2660);
DISPLAY 0.659574 (-1690 2660);
PAINT MONO (-1690 2660);
DISPLAY INVISIBLE (-1690 2660);
FORCEPROP 2 LAST CDS_LIB pure_quanta_power
J 0
(-1700 2600);
DISPLAY INVISIBLE (-1700 2600);
FORCEPROP 1 LAST PATH I123
J 0
(-1625 2600);
DISPLAY 0.872340 (-1625 2600);
PAINT AQUA (-1625 2600);
DISPLAY INVISIBLE (-1625 2600);
FORCEPROP 1 LAST HDL_POWER GND
J 1
(-1675 2525);
DISPLAY 0.872340 (-1675 2525);
PAINT GREEN (-1675 2525);
DISPLAY INVISIBLE (-1675 2525);
FORCEADD Q_CAP..1
(-5075 5375);
FORCEPROP 1 LAST LOCATION PC209_1
J 0
(-5025 5475);
DISPLAY 0.489362 (-5025 5475);
PAINT SKYBLUE (-5025 5475);
FORCEPROP 0 LAST $SEC 1
J 0
(-5025 5525);
DISPLAY 0.680851 (-5025 5525);
PAINT MONO (-5025 5525);
DISPLAY INVISIBLE (-5025 5525);
FORCEPROP 0 LAST CDS_SEC 1
J 0
(-5025 5525);
DISPLAY 1.021277 (-5025 5525);
DISPLAY INVISIBLE (-5025 5525);
FORCEPROP 1 LASTPIN (-5075 5475) $PN 1
J 0
(-5065 5455);
DISPLAY 0.489362 (-5065 5455);
PAINT MONO (-5065 5455);
FORCEPROP 1 LASTPIN (-5075 5275) $PN 2
J 0
(-5065 5255);
DISPLAY 0.489362 (-5065 5255);
PAINT MONO (-5065 5255);
FORCEPROP 1 LAST MATERIAL X7R
J 0
(-5025 5275);
DISPLAY 0.489362 (-5025 5275);
PAINT SKYBLUE (-5025 5275);
FORCEPROP 1 LAST TOLERANCE 10%
J 0
(-5025 5325);
DISPLAY 0.489362 (-5025 5325);
PAINT SKYBLUE (-5025 5325);
FORCEPROP 1 LAST VALUE 0.1UF
J 0
(-5025 5425);
DISPLAY 0.489362 (-5025 5425);
PAINT SKYBLUE (-5025 5425);
FORCEPROP 1 LAST PART_NUMBER CH4104K1B00
J 0
(-5025 5225);
DISPLAY 0.489362 (-5025 5225);
PAINT SKYBLUE (-5025 5225);
FORCEPROP 1 LAST VOLTAGE 25V
J 0
(-5025 5375);
DISPLAY 0.489362 (-5025 5375);
PAINT SKYBLUE (-5025 5375);
FORCEPROP 1 LAST PACK_TYPE 0402
J 0
(-5025 5175);
DISPLAY 0.489362 (-5025 5175);
PAINT SKYBLUE (-5025 5175);
FORCEPROP 2 LAST CDS_LIB pure_quanta
J 0
(-5075 5375);
DISPLAY INVISIBLE (-5075 5375);
FORCEPROP 1 LAST PATH I124
J 0
(-5025 5525);
DISPLAY 0.978723 (-5025 5525);
PAINT WHITE (-5025 5525);
DISPLAY INVISIBLE (-5025 5525);
FORCEADD Q_CAP..1
(-5025 2450);
FORCEPROP 1 LAST LOCATION PC210_2
J 0
(-4975 2550);
DISPLAY 0.489362 (-4975 2550);
PAINT SKYBLUE (-4975 2550);
FORCEPROP 0 LAST $SEC 1
J 0
(-4975 2600);
DISPLAY 0.680851 (-4975 2600);
PAINT MONO (-4975 2600);
DISPLAY INVISIBLE (-4975 2600);
FORCEPROP 0 LAST CDS_SEC 1
J 0
(-4975 2600);
DISPLAY 1.021277 (-4975 2600);
DISPLAY INVISIBLE (-4975 2600);
FORCEPROP 1 LASTPIN (-5025 2550) $PN 1
J 0
(-5015 2530);
DISPLAY 0.489362 (-5015 2530);
PAINT MONO (-5015 2530);
FORCEPROP 1 LASTPIN (-5025 2350) $PN 2
J 0
(-5015 2330);
DISPLAY 0.489362 (-5015 2330);
PAINT MONO (-5015 2330);
FORCEPROP 1 LAST MATERIAL X7R
J 0
(-4975 2350);
DISPLAY 0.489362 (-4975 2350);
PAINT SKYBLUE (-4975 2350);
FORCEPROP 1 LAST TOLERANCE 10%
J 0
(-4975 2400);
DISPLAY 0.489362 (-4975 2400);
PAINT SKYBLUE (-4975 2400);
FORCEPROP 1 LAST VALUE 0.1UF
J 0
(-4975 2500);
DISPLAY 0.489362 (-4975 2500);
PAINT SKYBLUE (-4975 2500);
FORCEPROP 1 LAST PART_NUMBER CH4104K1B00
J 0
(-4975 2300);
DISPLAY 0.489362 (-4975 2300);
PAINT SKYBLUE (-4975 2300);
FORCEPROP 1 LAST VOLTAGE 25V
J 0
(-4975 2450);
DISPLAY 0.489362 (-4975 2450);
PAINT SKYBLUE (-4975 2450);
FORCEPROP 1 LAST PACK_TYPE 0402
J 0
(-4975 2250);
DISPLAY 0.489362 (-4975 2250);
PAINT SKYBLUE (-4975 2250);
FORCEPROP 2 LAST CDS_LIB pure_quanta
J 0
(-5025 2450);
DISPLAY INVISIBLE (-5025 2450);
FORCEPROP 1 LAST PATH I125
J 0
(-4975 2600);
DISPLAY 0.978723 (-4975 2600);
PAINT WHITE (-4975 2600);
DISPLAY INVISIBLE (-4975 2600);
FORCEADD Q_CAP..1
(-7800 4800);
FORCEPROP 1 LAST LOCATION PC203
J 0
(-7750 4900);
DISPLAY 0.489362 (-7750 4900);
PAINT SKYBLUE (-7750 4900);
FORCEPROP 0 LAST $SEC 1
J 0
(-7750 4950);
DISPLAY 0.680851 (-7750 4950);
PAINT MONO (-7750 4950);
DISPLAY INVISIBLE (-7750 4950);
FORCEPROP 0 LAST CDS_SEC 1
J 0
(-7750 4950);
DISPLAY 1.021277 (-7750 4950);
DISPLAY INVISIBLE (-7750 4950);
FORCEPROP 1 LASTPIN (-7800 4900) $PN 1
J 0
(-7790 4880);
DISPLAY 0.489362 (-7790 4880);
PAINT MONO (-7790 4880);
FORCEPROP 1 LASTPIN (-7800 4700) $PN 2
J 0
(-7790 4680);
DISPLAY 0.489362 (-7790 4680);
PAINT MONO (-7790 4680);
FORCEPROP 1 LAST MATERIAL X6S
J 0
(-7750 4700);
DISPLAY 0.489362 (-7750 4700);
PAINT SKYBLUE (-7750 4700);
FORCEPROP 1 LAST TOLERANCE 10%
J 0
(-7750 4750);
DISPLAY 0.489362 (-7750 4750);
PAINT SKYBLUE (-7750 4750);
FORCEPROP 1 LAST VALUE 2.2UF
J 0
(-7750 4850);
DISPLAY 0.489362 (-7750 4850);
PAINT SKYBLUE (-7750 4850);
FORCEPROP 1 LAST PART_NUMBER CH5222KEB01
J 0
(-7750 4650);
DISPLAY 0.489362 (-7750 4650);
PAINT SKYBLUE (-7750 4650);
FORCEPROP 1 LAST VOLTAGE 10V
J 0
(-7750 4800);
DISPLAY 0.489362 (-7750 4800);
PAINT SKYBLUE (-7750 4800);
FORCEPROP 1 LAST PACK_TYPE C0402
J 0
(-7750 4600);
DISPLAY 0.489362 (-7750 4600);
PAINT SKYBLUE (-7750 4600);
FORCEPROP 2 LAST CDS_LIB pure_quanta
J 0
(-7800 4800);
DISPLAY INVISIBLE (-7800 4800);
FORCEPROP 1 LAST PATH I126
J 0
(-7750 4950);
DISPLAY 0.978723 (-7750 4950);
PAINT WHITE (-7750 4950);
DISPLAY INVISIBLE (-7750 4950);
FORCEADD UNIVERSAL_GND..1
(-7800 4600);
FORCEPROP 3 LASTPIN (-7800 4650) SIG_NAME GND\g
J 0
(-7790 4660);
DISPLAY 0.659574 (-7790 4660);
PAINT MONO (-7790 4660);
DISPLAY INVISIBLE (-7790 4660);
FORCEPROP 2 LAST CDS_LIB pure_quanta_power
J 0
(-7800 4600);
DISPLAY INVISIBLE (-7800 4600);
FORCEPROP 1 LAST PATH I127
J 0
(-7725 4600);
DISPLAY 0.872340 (-7725 4600);
PAINT AQUA (-7725 4600);
DISPLAY INVISIBLE (-7725 4600);
FORCEPROP 1 LAST HDL_POWER GND
J 1
(-7775 4525);
DISPLAY 0.872340 (-7775 4525);
PAINT GREEN (-7775 4525);
DISPLAY INVISIBLE (-7775 4525);
FORCEADD UNIVERSAL_GND..1
(-7450 5100);
FORCEPROP 3 LASTPIN (-7450 5150) SIG_NAME GND\g
J 0
(-7440 5160);
DISPLAY 0.659574 (-7440 5160);
PAINT MONO (-7440 5160);
DISPLAY INVISIBLE (-7440 5160);
FORCEPROP 2 LAST CDS_LIB pure_quanta_power
J 0
(-7450 5100);
DISPLAY INVISIBLE (-7450 5100);
FORCEPROP 1 LAST PATH I128
J 0
(-7375 5100);
DISPLAY 0.872340 (-7375 5100);
PAINT AQUA (-7375 5100);
DISPLAY INVISIBLE (-7375 5100);
FORCEPROP 1 LAST HDL_POWER GND
J 1
(-7425 5025);
DISPLAY 0.872340 (-7425 5025);
PAINT GREEN (-7425 5025);
DISPLAY INVISIBLE (-7425 5025);
FORCEADD Q_RES..2
(-7800 5350);
FORCEPROP 1 LAST LOCATION PR131
J 0
(-7755 5475);
DISPLAY 0.489362 (-7755 5475);
PAINT SKYBLUE (-7755 5475);
FORCEPROP 0 LAST $SEC 1
J 0
(-7750 5525);
DISPLAY 0.680851 (-7750 5525);
PAINT MONO (-7750 5525);
DISPLAY INVISIBLE (-7750 5525);
FORCEPROP 0 LAST CDS_SEC 1
J 0
(-7750 5525);
DISPLAY 1.021277 (-7750 5525);
DISPLAY INVISIBLE (-7750 5525);
FORCEPROP 1 LASTPIN (-7800 5450) $PN 1
J 0
(-7795 5412);
DISPLAY 0.489362 (-7795 5412);
PAINT MONO (-7795 5412);
FORCEPROP 1 LASTPIN (-7800 5250) $PN 2
J 0
(-7795 5260);
DISPLAY 0.489362 (-7795 5260);
PAINT MONO (-7795 5260);
FORCEPROP 1 LAST WATTAGE 1/16W
J 0
(-7750 5325);
DISPLAY 0.489362 (-7750 5325);
PAINT SKYBLUE (-7750 5325);
FORCEPROP 1 LAST MATERIAL CHIP
J 0
(-7750 5275);
DISPLAY 0.489362 (-7750 5275);
PAINT SKYBLUE (-7750 5275);
FORCEPROP 1 LAST TOLERANCE 1%
J 0
(-7750 5375);
DISPLAY 0.489362 (-7750 5375);
PAINT SKYBLUE (-7750 5375);
FORCEPROP 1 LAST VALUE 2.2
J 0
(-7750 5425);
DISPLAY 0.489362 (-7750 5425);
PAINT SKYBLUE (-7750 5425);
FORCEPROP 1 LAST PART_NUMBER CS-2202FB00
J 0
(-7750 5225);
DISPLAY 0.489362 (-7750 5225);
PAINT SKYBLUE (-7750 5225);
FORCEPROP 1 LAST PACK_TYPE 0402LF
J 0
(-7750 5175);
DISPLAY 0.489362 (-7750 5175);
PAINT SKYBLUE (-7750 5175);
FORCEPROP 2 LAST CDS_LIB pure_quanta
J 0
(-7800 5350);
DISPLAY INVISIBLE (-7800 5350);
FORCEPROP 1 LAST PATH I129
J 0
(-7750 5525);
DISPLAY 0.978723 (-7750 5525);
PAINT WHITE (-7750 5525);
DISPLAY INVISIBLE (-7750 5525);
FORCEADD Q_CAP..1
(-7450 5375);
FORCEPROP 1 LAST LOCATION PC205_11P0_1
J 0
(-7400 5475);
DISPLAY 0.489362 (-7400 5475);
PAINT SKYBLUE (-7400 5475);
FORCEPROP 0 LAST $SEC 1
J 0
(-7400 5525);
DISPLAY 0.680851 (-7400 5525);
PAINT MONO (-7400 5525);
DISPLAY INVISIBLE (-7400 5525);
FORCEPROP 0 LAST CDS_SEC 1
J 0
(-7400 5525);
DISPLAY 1.021277 (-7400 5525);
DISPLAY INVISIBLE (-7400 5525);
FORCEPROP 1 LASTPIN (-7450 5475) $PN 1
J 0
(-7440 5455);
DISPLAY 0.489362 (-7440 5455);
PAINT MONO (-7440 5455);
FORCEPROP 1 LASTPIN (-7450 5275) $PN 2
J 0
(-7440 5255);
DISPLAY 0.489362 (-7440 5255);
PAINT MONO (-7440 5255);
FORCEPROP 1 LAST MATERIAL X6S
J 0
(-7400 5275);
DISPLAY 0.489362 (-7400 5275);
PAINT SKYBLUE (-7400 5275);
FORCEPROP 1 LAST TOLERANCE 10%
J 0
(-7400 5325);
DISPLAY 0.489362 (-7400 5325);
PAINT SKYBLUE (-7400 5325);
FORCEPROP 1 LAST VALUE 2.2UF
J 0
(-7400 5425);
DISPLAY 0.489362 (-7400 5425);
PAINT SKYBLUE (-7400 5425);
FORCEPROP 1 LAST PART_NUMBER CH5222KEB01
J 0
(-7400 5225);
DISPLAY 0.489362 (-7400 5225);
PAINT SKYBLUE (-7400 5225);
FORCEPROP 1 LAST VOLTAGE 10V
J 0
(-7400 5375);
DISPLAY 0.489362 (-7400 5375);
PAINT SKYBLUE (-7400 5375);
FORCEPROP 1 LAST PACK_TYPE C0402
J 0
(-7400 5175);
DISPLAY 0.489362 (-7400 5175);
PAINT SKYBLUE (-7400 5175);
FORCEPROP 2 LAST CDS_LIB pure_quanta
J 0
(-7450 5375);
DISPLAY INVISIBLE (-7450 5375);
FORCEPROP 1 LAST PATH I130
J 0
(-7400 5525);
DISPLAY 0.978723 (-7400 5525);
PAINT WHITE (-7400 5525);
DISPLAY INVISIBLE (-7400 5525);
FORCEADD Q_CAP..1
(-7800 1875);
FORCEPROP 1 LAST LOCATION PC204
J 0
(-7750 1975);
DISPLAY 0.489362 (-7750 1975);
PAINT SKYBLUE (-7750 1975);
FORCEPROP 0 LAST $SEC 1
J 0
(-7750 2025);
DISPLAY 0.680851 (-7750 2025);
PAINT MONO (-7750 2025);
DISPLAY INVISIBLE (-7750 2025);
FORCEPROP 0 LAST CDS_SEC 1
J 0
(-7750 2025);
DISPLAY 1.021277 (-7750 2025);
DISPLAY INVISIBLE (-7750 2025);
FORCEPROP 1 LASTPIN (-7800 1975) $PN 1
J 0
(-7790 1955);
DISPLAY 0.489362 (-7790 1955);
PAINT MONO (-7790 1955);
FORCEPROP 1 LASTPIN (-7800 1775) $PN 2
J 0
(-7790 1755);
DISPLAY 0.489362 (-7790 1755);
PAINT MONO (-7790 1755);
FORCEPROP 1 LAST MATERIAL X6S
J 0
(-7750 1775);
DISPLAY 0.489362 (-7750 1775);
PAINT SKYBLUE (-7750 1775);
FORCEPROP 1 LAST TOLERANCE 10%
J 0
(-7750 1825);
DISPLAY 0.489362 (-7750 1825);
PAINT SKYBLUE (-7750 1825);
FORCEPROP 1 LAST VALUE 2.2UF
J 0
(-7750 1925);
DISPLAY 0.489362 (-7750 1925);
PAINT SKYBLUE (-7750 1925);
FORCEPROP 1 LAST PART_NUMBER CH5222KEB01
J 0
(-7750 1725);
DISPLAY 0.489362 (-7750 1725);
PAINT SKYBLUE (-7750 1725);
FORCEPROP 1 LAST VOLTAGE 10V
J 0
(-7750 1875);
DISPLAY 0.489362 (-7750 1875);
PAINT SKYBLUE (-7750 1875);
FORCEPROP 1 LAST PACK_TYPE C0402
J 0
(-7750 1675);
DISPLAY 0.489362 (-7750 1675);
PAINT SKYBLUE (-7750 1675);
FORCEPROP 2 LAST CDS_LIB pure_quanta
J 0
(-7800 1875);
DISPLAY INVISIBLE (-7800 1875);
FORCEPROP 1 LAST PATH I132
J 0
(-7750 2025);
DISPLAY 0.978723 (-7750 2025);
PAINT WHITE (-7750 2025);
DISPLAY INVISIBLE (-7750 2025);
FORCEADD UNIVERSAL_GND..1
(-7800 1675);
FORCEPROP 3 LASTPIN (-7800 1725) SIG_NAME GND\g
J 0
(-7790 1735);
DISPLAY 0.659574 (-7790 1735);
PAINT MONO (-7790 1735);
DISPLAY INVISIBLE (-7790 1735);
FORCEPROP 2 LAST CDS_LIB pure_quanta_power
J 0
(-7800 1675);
DISPLAY INVISIBLE (-7800 1675);
FORCEPROP 1 LAST PATH I133
J 0
(-7725 1675);
DISPLAY 0.872340 (-7725 1675);
PAINT AQUA (-7725 1675);
DISPLAY INVISIBLE (-7725 1675);
FORCEPROP 1 LAST HDL_POWER GND
J 1
(-7775 1600);
DISPLAY 0.872340 (-7775 1600);
PAINT GREEN (-7775 1600);
DISPLAY INVISIBLE (-7775 1600);
FORCEADD UNIVERSAL_GND..1
(-7450 2175);
FORCEPROP 3 LASTPIN (-7450 2225) SIG_NAME GND\g
J 0
(-7440 2235);
DISPLAY 0.659574 (-7440 2235);
PAINT MONO (-7440 2235);
DISPLAY INVISIBLE (-7440 2235);
FORCEPROP 2 LAST CDS_LIB pure_quanta_power
J 0
(-7450 2175);
DISPLAY INVISIBLE (-7450 2175);
FORCEPROP 1 LAST PATH I134
J 0
(-7375 2175);
DISPLAY 0.872340 (-7375 2175);
PAINT AQUA (-7375 2175);
DISPLAY INVISIBLE (-7375 2175);
FORCEPROP 1 LAST HDL_POWER GND
J 1
(-7425 2100);
DISPLAY 0.872340 (-7425 2100);
PAINT GREEN (-7425 2100);
DISPLAY INVISIBLE (-7425 2100);
FORCEADD Q_RES..2
(-7800 2425);
FORCEPROP 1 LAST LOCATION PR132
J 0
(-7755 2550);
DISPLAY 0.489362 (-7755 2550);
PAINT SKYBLUE (-7755 2550);
FORCEPROP 0 LAST $SEC 1
J 0
(-7750 2600);
DISPLAY 0.680851 (-7750 2600);
PAINT MONO (-7750 2600);
DISPLAY INVISIBLE (-7750 2600);
FORCEPROP 0 LAST CDS_SEC 1
J 0
(-7750 2600);
DISPLAY 1.021277 (-7750 2600);
DISPLAY INVISIBLE (-7750 2600);
FORCEPROP 1 LASTPIN (-7800 2525) $PN 1
J 0
(-7795 2487);
DISPLAY 0.489362 (-7795 2487);
PAINT MONO (-7795 2487);
FORCEPROP 1 LASTPIN (-7800 2325) $PN 2
J 0
(-7795 2335);
DISPLAY 0.489362 (-7795 2335);
PAINT MONO (-7795 2335);
FORCEPROP 1 LAST WATTAGE 1/16W
J 0
(-7750 2400);
DISPLAY 0.489362 (-7750 2400);
PAINT SKYBLUE (-7750 2400);
FORCEPROP 1 LAST MATERIAL CHIP
J 0
(-7750 2350);
DISPLAY 0.489362 (-7750 2350);
PAINT SKYBLUE (-7750 2350);
FORCEPROP 1 LAST TOLERANCE 1%
J 0
(-7750 2450);
DISPLAY 0.489362 (-7750 2450);
PAINT SKYBLUE (-7750 2450);
FORCEPROP 1 LAST VALUE 2.2
J 0
(-7750 2500);
DISPLAY 0.489362 (-7750 2500);
PAINT SKYBLUE (-7750 2500);
FORCEPROP 1 LAST PART_NUMBER CS-2202FB00
J 0
(-7750 2300);
DISPLAY 0.489362 (-7750 2300);
PAINT SKYBLUE (-7750 2300);
FORCEPROP 1 LAST PACK_TYPE 0402LF
J 0
(-7750 2250);
DISPLAY 0.489362 (-7750 2250);
PAINT SKYBLUE (-7750 2250);
FORCEPROP 2 LAST CDS_LIB pure_quanta
J 0
(-7800 2425);
DISPLAY INVISIBLE (-7800 2425);
FORCEPROP 1 LAST PATH I135
J 0
(-7750 2600);
DISPLAY 0.978723 (-7750 2600);
PAINT WHITE (-7750 2600);
DISPLAY INVISIBLE (-7750 2600);
FORCEADD Q_CAP..1
(-7450 2450);
FORCEPROP 1 LAST LOCATION PC206_11P0_2
J 0
(-7400 2550);
DISPLAY 0.489362 (-7400 2550);
PAINT SKYBLUE (-7400 2550);
FORCEPROP 0 LAST $SEC 1
J 0
(-7400 2600);
DISPLAY 0.680851 (-7400 2600);
PAINT MONO (-7400 2600);
DISPLAY INVISIBLE (-7400 2600);
FORCEPROP 0 LAST CDS_SEC 1
J 0
(-7400 2600);
DISPLAY 1.021277 (-7400 2600);
DISPLAY INVISIBLE (-7400 2600);
FORCEPROP 1 LASTPIN (-7450 2550) $PN 1
J 0
(-7440 2530);
DISPLAY 0.489362 (-7440 2530);
PAINT MONO (-7440 2530);
FORCEPROP 1 LASTPIN (-7450 2350) $PN 2
J 0
(-7440 2330);
DISPLAY 0.489362 (-7440 2330);
PAINT MONO (-7440 2330);
FORCEPROP 1 LAST MATERIAL X6S
J 0
(-7400 2350);
DISPLAY 0.489362 (-7400 2350);
PAINT SKYBLUE (-7400 2350);
FORCEPROP 1 LAST TOLERANCE 10%
J 0
(-7400 2400);
DISPLAY 0.489362 (-7400 2400);
PAINT SKYBLUE (-7400 2400);
FORCEPROP 1 LAST VALUE 2.2UF
J 0
(-7400 2500);
DISPLAY 0.489362 (-7400 2500);
PAINT SKYBLUE (-7400 2500);
FORCEPROP 1 LAST PART_NUMBER CH5222KEB01
J 0
(-7400 2300);
DISPLAY 0.489362 (-7400 2300);
PAINT SKYBLUE (-7400 2300);
FORCEPROP 1 LAST VOLTAGE 10V
J 0
(-7400 2450);
DISPLAY 0.489362 (-7400 2450);
PAINT SKYBLUE (-7400 2450);
FORCEPROP 1 LAST PACK_TYPE C0402
J 0
(-7400 2250);
DISPLAY 0.489362 (-7400 2250);
PAINT SKYBLUE (-7400 2250);
FORCEPROP 2 LAST CDS_LIB pure_quanta
J 0
(-7450 2450);
DISPLAY INVISIBLE (-7450 2450);
FORCEPROP 1 LAST PATH I136
J 0
(-7400 2600);
DISPLAY 0.978723 (-7400 2600);
PAINT WHITE (-7400 2600);
DISPLAY INVISIBLE (-7400 2600);
FORCEADD Q_CAP..1
(-3750 5375);
FORCEPROP 1 LAST LOCATION PC219_1
J 0
(-3700 5475);
DISPLAY 0.489362 (-3700 5475);
PAINT SKYBLUE (-3700 5475);
FORCEPROP 0 LAST $SEC 1
J 0
(-3700 5500);
DISPLAY 0.680851 (-3700 5500);
PAINT MONO (-3700 5500);
DISPLAY INVISIBLE (-3700 5500);
FORCEPROP 0 LAST CDS_SEC 1
J 0
(-3700 5500);
DISPLAY 1.021277 (-3700 5500);
DISPLAY INVISIBLE (-3700 5500);
FORCEPROP 1 LASTPIN (-3750 5475) $PN 1
J 0
(-3740 5455);
DISPLAY 0.489362 (-3740 5455);
PAINT MONO (-3740 5455);
FORCEPROP 1 LASTPIN (-3750 5275) $PN 2
J 0
(-3740 5255);
DISPLAY 0.489362 (-3740 5255);
PAINT MONO (-3740 5255);
FORCEPROP 1 LAST MATERIAL X6S
J 0
(-3700 5275);
DISPLAY 0.489362 (-3700 5275);
PAINT SKYBLUE (-3700 5275);
FORCEPROP 1 LAST TOLERANCE 10%
J 0
(-3700 5325);
DISPLAY 0.489362 (-3700 5325);
PAINT SKYBLUE (-3700 5325);
FORCEPROP 1 LAST VALUE 10UF
J 0
(-3700 5425);
DISPLAY 0.489362 (-3700 5425);
PAINT SKYBLUE (-3700 5425);
FORCEPROP 1 LAST PART_NUMBER CH6104KEA00
J 0
(-3700 5225);
DISPLAY 0.489362 (-3700 5225);
PAINT SKYBLUE (-3700 5225);
FORCEPROP 1 LAST VOLTAGE 25V
J 0
(-3700 5375);
DISPLAY 0.489362 (-3700 5375);
PAINT SKYBLUE (-3700 5375);
FORCEPROP 1 LAST PACK_TYPE C0805
J 0
(-3700 5175);
DISPLAY 0.489362 (-3700 5175);
PAINT SKYBLUE (-3700 5175);
FORCEPROP 2 LAST CDS_LIB pure_quanta
J 0
(-3750 5375);
DISPLAY INVISIBLE (-3750 5375);
FORCEPROP 1 LAST PATH I138
J 0
(-3700 5525);
DISPLAY 0.978723 (-3700 5525);
PAINT WHITE (-3700 5525);
DISPLAY INVISIBLE (-3700 5525);
FORCEADD Q_CAP..1
(-3725 2450);
FORCEPROP 1 LAST LOCATION PC218_2
J 0
(-3675 2550);
DISPLAY 0.489362 (-3675 2550);
PAINT SKYBLUE (-3675 2550);
FORCEPROP 0 LAST $SEC 1
J 0
(-3675 2575);
DISPLAY 0.680851 (-3675 2575);
PAINT MONO (-3675 2575);
DISPLAY INVISIBLE (-3675 2575);
FORCEPROP 0 LAST CDS_SEC 1
J 0
(-3675 2575);
DISPLAY 1.021277 (-3675 2575);
DISPLAY INVISIBLE (-3675 2575);
FORCEPROP 1 LASTPIN (-3725 2550) $PN 1
J 0
(-3715 2530);
DISPLAY 0.489362 (-3715 2530);
PAINT MONO (-3715 2530);
FORCEPROP 1 LASTPIN (-3725 2350) $PN 2
J 0
(-3715 2330);
DISPLAY 0.489362 (-3715 2330);
PAINT MONO (-3715 2330);
FORCEPROP 1 LAST PACK_TYPE C0805
J 0
(-3675 2250);
DISPLAY 0.489362 (-3675 2250);
PAINT SKYBLUE (-3675 2250);
FORCEPROP 1 LAST PART_NUMBER CH6104KEA00
J 0
(-3675 2300);
DISPLAY 0.489362 (-3675 2300);
PAINT SKYBLUE (-3675 2300);
FORCEPROP 1 LAST MATERIAL X6S
J 0
(-3675 2350);
DISPLAY 0.489362 (-3675 2350);
PAINT SKYBLUE (-3675 2350);
FORCEPROP 1 LAST TOLERANCE 10%
J 0
(-3675 2400);
DISPLAY 0.489362 (-3675 2400);
PAINT SKYBLUE (-3675 2400);
FORCEPROP 1 LAST VALUE 10UF
J 0
(-3675 2500);
DISPLAY 0.489362 (-3675 2500);
PAINT SKYBLUE (-3675 2500);
FORCEPROP 1 LAST VOLTAGE 25V
J 0
(-3675 2450);
DISPLAY 0.489362 (-3675 2450);
PAINT SKYBLUE (-3675 2450);
FORCEPROP 2 LAST CDS_LIB pure_quanta
J 0
(-3725 2450);
DISPLAY INVISIBLE (-3725 2450);
FORCEPROP 1 LAST PATH I139
J 0
(-3675 2600);
DISPLAY 0.978723 (-3675 2600);
PAINT WHITE (-3675 2600);
DISPLAY INVISIBLE (-3675 2600);
FORCEADD UNIVERSAL_GND..1
(-4575 650);
FORCEPROP 3 LASTPIN (-4575 700) SIG_NAME GND\g
J 0
(-4565 710);
DISPLAY 0.659574 (-4565 710);
PAINT MONO (-4565 710);
DISPLAY INVISIBLE (-4565 710);
FORCEPROP 2 LAST CDS_LIB pure_quanta_power
J 0
(-4575 650);
DISPLAY INVISIBLE (-4575 650);
FORCEPROP 1 LAST PATH I140
J 0
(-4500 650);
DISPLAY 0.872340 (-4500 650);
PAINT AQUA (-4500 650);
DISPLAY INVISIBLE (-4500 650);
FORCEPROP 1 LAST HDL_POWER GND
J 1
(-4550 575);
DISPLAY 0.872340 (-4550 575);
PAINT GREEN (-4550 575);
DISPLAY INVISIBLE (-4550 575);
FORCEADD Q_RES..2
(-4575 875);
FORCEPROP 1 LAST LOCATION PR389
J 0
(-4530 1000);
DISPLAY 0.489362 (-4530 1000);
PAINT SKYBLUE (-4530 1000);
FORCEPROP 0 LAST $SEC 1
J 0
(-4525 1050);
DISPLAY 0.680851 (-4525 1050);
PAINT MONO (-4525 1050);
DISPLAY INVISIBLE (-4525 1050);
FORCEPROP 0 LAST CDS_SEC 1
J 0
(-4525 1050);
DISPLAY 1.021277 (-4525 1050);
DISPLAY INVISIBLE (-4525 1050);
FORCEPROP 1 LASTPIN (-4575 975) $PN 1
J 0
(-4570 937);
DISPLAY 0.489362 (-4570 937);
PAINT MONO (-4570 937);
FORCEPROP 1 LASTPIN (-4575 775) $PN 2
J 0
(-4570 785);
DISPLAY 0.489362 (-4570 785);
PAINT MONO (-4570 785);
FORCEPROP 1 LAST WATTAGE 1/8W
J 0
(-4535 850);
DISPLAY 0.489362 (-4535 850);
PAINT SKYBLUE (-4535 850);
FORCEPROP 1 LAST MATERIAL EMPTY
J 0
(-4535 800);
DISPLAY 0.489362 (-4535 800);
PAINT RED (-4535 800);
FORCEPROP 1 LAST TOLERANCE 1%
J 0
(-4530 900);
DISPLAY 0.489362 (-4530 900);
PAINT SKYBLUE (-4530 900);
FORCEPROP 1 LAST VALUE 1.5
J 0
(-4530 950);
DISPLAY 0.489362 (-4530 950);
PAINT SKYBLUE (-4530 950);
FORCEPROP 1 LAST PART_NUMBER CS-1504FB00
J 0
(-4535 750);
DISPLAY 0.489362 (-4535 750);
PAINT SKYBLUE (-4535 750);
FORCEPROP 1 LAST PACK_TYPE 0402LF
J 0
(-4535 700);
DISPLAY 0.489362 (-4535 700);
PAINT SKYBLUE (-4535 700);
FORCEPROP 2 LAST CDS_LIB pure_quanta
J 0
(-4575 875);
DISPLAY INVISIBLE (-4575 875);
FORCEPROP 1 LAST PATH I141
J 0
(-4525 1050);
DISPLAY 0.978723 (-4525 1050);
PAINT WHITE (-4525 1050);
DISPLAY INVISIBLE (-4525 1050);
FORCEADD Q_CAP..1
(-4575 1350);
FORCEPROP 1 LAST LOCATION PC168
J 0
(-4525 1450);
DISPLAY 0.489362 (-4525 1450);
PAINT SKYBLUE (-4525 1450);
FORCEPROP 0 LAST $SEC 1
J 0
(-4525 1500);
DISPLAY 0.680851 (-4525 1500);
PAINT MONO (-4525 1500);
DISPLAY INVISIBLE (-4525 1500);
FORCEPROP 0 LAST CDS_SEC 1
J 0
(-4525 1500);
DISPLAY 1.021277 (-4525 1500);
DISPLAY INVISIBLE (-4525 1500);
FORCEPROP 1 LASTPIN (-4575 1450) $PN 1
J 0
(-4565 1430);
DISPLAY 0.489362 (-4565 1430);
PAINT MONO (-4565 1430);
FORCEPROP 1 LASTPIN (-4575 1250) $PN 2
J 0
(-4565 1230);
DISPLAY 0.489362 (-4565 1230);
PAINT MONO (-4565 1230);
FORCEPROP 1 LAST MATERIAL EMPTY
J 0
(-4525 1250);
DISPLAY 0.489362 (-4525 1250);
PAINT RED (-4525 1250);
FORCEPROP 1 LAST TOLERANCE 10%
J 0
(-4525 1300);
DISPLAY 0.489362 (-4525 1300);
PAINT SKYBLUE (-4525 1300);
FORCEPROP 1 LAST VALUE 560PF
J 0
(-4525 1400);
DISPLAY 0.489362 (-4525 1400);
PAINT SKYBLUE (-4525 1400);
FORCEPROP 1 LAST PART_NUMBER CH1566K1B09
J 0
(-4525 1200);
DISPLAY 0.489362 (-4525 1200);
PAINT SKYBLUE (-4525 1200);
FORCEPROP 1 LAST VOLTAGE 50V
J 0
(-4525 1350);
DISPLAY 0.489362 (-4525 1350);
PAINT SKYBLUE (-4525 1350);
FORCEPROP 1 LAST PACK_TYPE C0402
J 0
(-4525 1150);
DISPLAY 0.489362 (-4525 1150);
PAINT SKYBLUE (-4525 1150);
FORCEPROP 2 LAST CDS_LIB pure_quanta
J 0
(-4575 1350);
DISPLAY INVISIBLE (-4575 1350);
FORCEPROP 1 LAST PATH I142
J 0
(-4525 1500);
DISPLAY 0.978723 (-4525 1500);
PAINT WHITE (-4525 1500);
DISPLAY INVISIBLE (-4525 1500);
FORCEADD UNIVERSAL_GND..1
(-4675 3575);
FORCEPROP 3 LASTPIN (-4675 3625) SIG_NAME GND\g
J 0
(-4665 3635);
DISPLAY 0.659574 (-4665 3635);
PAINT MONO (-4665 3635);
DISPLAY INVISIBLE (-4665 3635);
FORCEPROP 2 LAST CDS_LIB pure_quanta_power
J 0
(-4675 3575);
DISPLAY INVISIBLE (-4675 3575);
FORCEPROP 1 LAST PATH I143
J 0
(-4600 3575);
DISPLAY 0.872340 (-4600 3575);
PAINT AQUA (-4600 3575);
DISPLAY INVISIBLE (-4600 3575);
FORCEPROP 1 LAST HDL_POWER GND
J 1
(-4650 3500);
DISPLAY 0.872340 (-4650 3500);
PAINT GREEN (-4650 3500);
DISPLAY INVISIBLE (-4650 3500);
FORCEADD Q_RES..2
(-4675 3800);
FORCEPROP 1 LAST LOCATION PR482
J 0
(-4630 3925);
DISPLAY 0.489362 (-4630 3925);
PAINT SKYBLUE (-4630 3925);
FORCEPROP 0 LAST $SEC 1
J 0
(-4625 3975);
DISPLAY 0.680851 (-4625 3975);
PAINT MONO (-4625 3975);
DISPLAY INVISIBLE (-4625 3975);
FORCEPROP 0 LAST CDS_SEC 1
J 0
(-4625 3975);
DISPLAY 1.021277 (-4625 3975);
DISPLAY INVISIBLE (-4625 3975);
FORCEPROP 1 LASTPIN (-4675 3900) $PN 1
J 0
(-4670 3862);
DISPLAY 0.489362 (-4670 3862);
PAINT MONO (-4670 3862);
FORCEPROP 1 LASTPIN (-4675 3700) $PN 2
J 0
(-4670 3710);
DISPLAY 0.489362 (-4670 3710);
PAINT MONO (-4670 3710);
FORCEPROP 1 LAST WATTAGE 1/8W
J 0
(-4635 3775);
DISPLAY 0.489362 (-4635 3775);
PAINT SKYBLUE (-4635 3775);
FORCEPROP 1 LAST MATERIAL EMPTY
J 0
(-4635 3725);
DISPLAY 0.489362 (-4635 3725);
PAINT RED (-4635 3725);
FORCEPROP 1 LAST TOLERANCE 1%
J 0
(-4630 3825);
DISPLAY 0.489362 (-4630 3825);
PAINT SKYBLUE (-4630 3825);
FORCEPROP 1 LAST VALUE 1.5
J 0
(-4630 3875);
DISPLAY 0.489362 (-4630 3875);
PAINT SKYBLUE (-4630 3875);
FORCEPROP 1 LAST PART_NUMBER CS-1504FB00
J 0
(-4635 3675);
DISPLAY 0.489362 (-4635 3675);
PAINT SKYBLUE (-4635 3675);
FORCEPROP 1 LAST PACK_TYPE 0402LF
J 0
(-4635 3625);
DISPLAY 0.489362 (-4635 3625);
PAINT SKYBLUE (-4635 3625);
FORCEPROP 2 LAST CDS_LIB pure_quanta
J 0
(-4675 3800);
DISPLAY INVISIBLE (-4675 3800);
FORCEPROP 1 LAST PATH I144
J 0
(-4625 3975);
DISPLAY 0.978723 (-4625 3975);
PAINT WHITE (-4625 3975);
DISPLAY INVISIBLE (-4625 3975);
FORCEADD Q_CAP..1
(-4675 4275);
FORCEPROP 1 LAST LOCATION PC169
J 0
(-4625 4375);
DISPLAY 0.489362 (-4625 4375);
PAINT SKYBLUE (-4625 4375);
FORCEPROP 0 LAST $SEC 1
J 0
(-4625 4425);
DISPLAY 0.680851 (-4625 4425);
PAINT MONO (-4625 4425);
DISPLAY INVISIBLE (-4625 4425);
FORCEPROP 0 LAST CDS_SEC 1
J 0
(-4625 4425);
DISPLAY 1.021277 (-4625 4425);
DISPLAY INVISIBLE (-4625 4425);
FORCEPROP 1 LASTPIN (-4675 4375) $PN 1
J 0
(-4665 4355);
DISPLAY 0.489362 (-4665 4355);
PAINT MONO (-4665 4355);
FORCEPROP 1 LASTPIN (-4675 4175) $PN 2
J 0
(-4665 4155);
DISPLAY 0.489362 (-4665 4155);
PAINT MONO (-4665 4155);
FORCEPROP 1 LAST MATERIAL EMPTY
J 0
(-4625 4175);
DISPLAY 0.489362 (-4625 4175);
PAINT RED (-4625 4175);
FORCEPROP 1 LAST TOLERANCE 10%
J 0
(-4625 4225);
DISPLAY 0.489362 (-4625 4225);
PAINT SKYBLUE (-4625 4225);
FORCEPROP 1 LAST VALUE 560PF
J 0
(-4625 4325);
DISPLAY 0.489362 (-4625 4325);
PAINT SKYBLUE (-4625 4325);
FORCEPROP 1 LAST PART_NUMBER CH1566K1B09
J 0
(-4625 4125);
DISPLAY 0.489362 (-4625 4125);
PAINT SKYBLUE (-4625 4125);
FORCEPROP 1 LAST VOLTAGE 50V
J 0
(-4625 4275);
DISPLAY 0.489362 (-4625 4275);
PAINT SKYBLUE (-4625 4275);
FORCEPROP 1 LAST PACK_TYPE C0402
J 0
(-4625 4075);
DISPLAY 0.489362 (-4625 4075);
PAINT SKYBLUE (-4625 4075);
FORCEPROP 2 LAST CDS_LIB pure_quanta
J 0
(-4675 4275);
DISPLAY INVISIBLE (-4675 4275);
FORCEPROP 1 LAST PATH I145
J 0
(-4625 4425);
DISPLAY 0.978723 (-4625 4425);
PAINT WHITE (-4625 4425);
DISPLAY INVISIBLE (-4625 4425);
FORCEADD VCC_CORE..1
(-7600 5950);
FORCEPROP 3 LASTPIN (-7600 5900) SIG_NAME PVDD11_S3_P0_PVCC\g
J 0
(-7590 5910);
DISPLAY 0.659574 (-7590 5910);
PAINT MONO (-7590 5910);
DISPLAY INVISIBLE (-7590 5910);
FORCEPROP 1 LAST HDL_POWER PVDD11_S3_P0_PVCC
J 1
(-7600 6000);
DISPLAY 0.489362 (-7600 6000);
PAINT GREEN (-7600 6000);
FORCEPROP 2 LAST CDS_LIB pure_quanta_power
J 0
(-7600 5950);
DISPLAY INVISIBLE (-7600 5950);
FORCEPROP 1 LAST PATH I146
J 0
(-7550 5975);
DISPLAY 0.872340 (-7550 5975);
PAINT AQUA (-7550 5975);
DISPLAY INVISIBLE (-7550 5975);
FORCEADD VCC_CORE..1
(-7800 2850);
FORCEPROP 3 LASTPIN (-7800 2800) SIG_NAME PVDD11_S3_P0_PVCC\g
J 0
(-7790 2810);
DISPLAY 0.659574 (-7790 2810);
PAINT MONO (-7790 2810);
DISPLAY INVISIBLE (-7790 2810);
FORCEPROP 1 LAST HDL_POWER PVDD11_S3_P0_PVCC
J 1
(-7800 2900);
DISPLAY 0.489362 (-7800 2900);
PAINT GREEN (-7800 2900);
FORCEPROP 2 LAST CDS_LIB pure_quanta_power
J 0
(-7800 2850);
DISPLAY INVISIBLE (-7800 2850);
FORCEPROP 1 LAST PATH I147
J 0
(-7750 2875);
DISPLAY 0.872340 (-7750 2875);
PAINT AQUA (-7750 2875);
DISPLAY INVISIBLE (-7750 2875);
FORCEADD VCC_CORE..1
(-8100 5950);
FORCEPROP 3 LASTPIN (-8100 5900) SIG_NAME P3V3_STBY\g
J 0
(-8090 5910);
DISPLAY 0.659574 (-8090 5910);
PAINT MONO (-8090 5910);
DISPLAY INVISIBLE (-8090 5910);
FORCEPROP 1 LAST HDL_POWER P3V3_STBY
J 1
(-8100 6000);
DISPLAY 0.489362 (-8100 6000);
PAINT GREEN (-8100 6000);
FORCEPROP 2 LAST CDS_LIB pure_quanta_power
J 0
(-8100 5950);
DISPLAY INVISIBLE (-8100 5950);
FORCEPROP 1 LAST PATH I148
J 0
(-8050 5975);
DISPLAY 0.872340 (-8050 5975);
PAINT AQUA (-8050 5975);
DISPLAY INVISIBLE (-8050 5975);
FORCEADD Q_RES..1
R 1
(-8100 5750);
FORCEPROP 1 LAST LOCATION PR413
J 0
(-8050 5900);
DISPLAY 0.489362 (-8050 5900);
PAINT SKYBLUE (-8050 5900);
FORCEPROP 0 LAST $SEC 1
R 1
J 0
(-8050 5925);
DISPLAY 0.680851 (-8050 5925);
PAINT MONO (-8050 5925);
DISPLAY INVISIBLE (-8050 5925);
FORCEPROP 0 LAST CDS_SEC 1
R 1
J 0
(-8050 5925);
DISPLAY 1.021277 (-8050 5925);
DISPLAY INVISIBLE (-8050 5925);
FORCEPROP 1 LASTPIN (-8100 5650) $PN 1
R 1
J 0
(-8112 5662);
DISPLAY 0.787234 (-8112 5662);
PAINT MONO (-8112 5662);
DISPLAY INVISIBLE (-8112 5662);
FORCEPROP 1 LASTPIN (-8100 5850) $PN 2
R 1
J 0
(-8112 5812);
DISPLAY 0.787234 (-8112 5812);
PAINT MONO (-8112 5812);
DISPLAY INVISIBLE (-8112 5812);
FORCEPROP 1 LAST WATTAGE 1/16W
J 0
(-8050 5750);
DISPLAY 0.489362 (-8050 5750);
PAINT SKYBLUE (-8050 5750);
FORCEPROP 1 LAST MATERIAL EMPTY
J 0
(-8050 5700);
DISPLAY 0.489362 (-8050 5700);
PAINT RED (-8050 5700);
FORCEPROP 1 LAST TOLERANCE 5%
J 0
(-8050 5800);
DISPLAY 0.489362 (-8050 5800);
PAINT SKYBLUE (-8050 5800);
FORCEPROP 1 LAST VALUE 0
J 2
(-8025 5850);
DISPLAY 0.489362 (-8025 5850);
PAINT SKYBLUE (-8025 5850);
FORCEPROP 1 LAST PART_NUMBER CS00002JB38
J 0
(-8050 5650);
DISPLAY 0.489362 (-8050 5650);
PAINT SKYBLUE (-8050 5650);
FORCEPROP 1 LAST PACK_TYPE 0402LF
J 0
(-8050 5600);
DISPLAY 0.489362 (-8050 5600);
PAINT SKYBLUE (-8050 5600);
FORCEPROP 2 LAST CDS_LIB pure_quanta
J 0
(-8100 5750);
DISPLAY INVISIBLE (-8100 5750);
FORCEPROP 1 LAST PATH I149
R 1
J 0
(-8250 5700);
DISPLAY 0.978723 (-8250 5700);
PAINT WHITE (-8250 5700);
DISPLAY INVISIBLE (-8250 5700);
FORCEADD Q_RES..1
(-7225 4175);
FORCEPROP 1 LAST LOCATION PR133
J 0
(-7225 4225);
DISPLAY 0.489362 (-7225 4225);
PAINT SKYBLUE (-7225 4225);
FORCEPROP 0 LAST $SEC 1
J 0
(-7225 4250);
DISPLAY 0.680851 (-7225 4250);
PAINT MONO (-7225 4250);
DISPLAY INVISIBLE (-7225 4250);
FORCEPROP 0 LAST CDS_SEC 1
J 0
(-7225 4250);
DISPLAY 1.021277 (-7225 4250);
DISPLAY INVISIBLE (-7225 4250);
FORCEPROP 1 LASTPIN (-7325 4175) $PN 1
J 0
(-7313 4187);
DISPLAY 0.489362 (-7313 4187);
PAINT MONO (-7313 4187);
FORCEPROP 1 LASTPIN (-7125 4175) $PN 2
J 0
(-7163 4187);
DISPLAY 0.489362 (-7163 4187);
PAINT MONO (-7163 4187);
FORCEPROP 1 LAST WATTAGE 1/16W
J 0
(-7125 4075);
DISPLAY 0.489362 (-7125 4075);
PAINT SKYBLUE (-7125 4075);
FORCEPROP 1 LAST MATERIAL EMPTY
J 0
(-7525 4075);
DISPLAY 0.489362 (-7525 4075);
PAINT RED (-7525 4075);
FORCEPROP 1 LAST TOLERANCE 1%
J 0
(-7100 4200);
DISPLAY 0.489362 (-7100 4200);
PAINT SKYBLUE (-7100 4200);
FORCEPROP 1 LAST VALUE 4.87K
J 2
(-7300 4200);
DISPLAY 0.489362 (-7300 4200);
PAINT SKYBLUE (-7300 4200);
FORCEPROP 1 LAST PART_NUMBER CS24872FB07
J 0
(-7525 4125);
DISPLAY 0.489362 (-7525 4125);
PAINT SKYBLUE (-7525 4125);
FORCEPROP 1 LAST PACK_TYPE 0402LF
J 0
(-7125 4125);
DISPLAY 0.489362 (-7125 4125);
PAINT SKYBLUE (-7125 4125);
FORCEPROP 2 LAST CDS_LIB pure_quanta
J 0
(-7225 4175);
DISPLAY INVISIBLE (-7225 4175);
FORCEPROP 1 LAST PATH I15
J 0
(-7275 4325);
DISPLAY 0.978723 (-7275 4325);
PAINT WHITE (-7275 4325);
DISPLAY INVISIBLE (-7275 4325);
FORCEADD VCC_CORE..1
(-8450 5950);
FORCEPROP 3 LASTPIN (-8450 5900) SIG_NAME P5V_STBY\g
J 0
(-8440 5910);
DISPLAY 0.659574 (-8440 5910);
PAINT MONO (-8440 5910);
DISPLAY INVISIBLE (-8440 5910);
FORCEPROP 1 LAST HDL_POWER P5V_STBY
J 1
(-8450 6000);
DISPLAY 0.489362 (-8450 6000);
PAINT GREEN (-8450 6000);
FORCEPROP 2 LAST CDS_LIB pure_quanta_power
J 0
(-8450 5950);
DISPLAY INVISIBLE (-8450 5950);
FORCEPROP 1 LAST PATH I150
J 0
(-8400 5975);
DISPLAY 0.872340 (-8400 5975);
PAINT AQUA (-8400 5975);
DISPLAY INVISIBLE (-8400 5975);
FORCEADD Q_RES..1
R 1
(-8450 5750);
FORCEPROP 1 LAST LOCATION PR411
J 0
(-8400 5900);
DISPLAY 0.489362 (-8400 5900);
PAINT SKYBLUE (-8400 5900);
FORCEPROP 0 LAST $SEC 1
R 1
J 0
(-8400 5925);
DISPLAY 0.680851 (-8400 5925);
PAINT MONO (-8400 5925);
DISPLAY INVISIBLE (-8400 5925);
FORCEPROP 0 LAST CDS_SEC 1
R 1
J 0
(-8400 5925);
DISPLAY 1.021277 (-8400 5925);
DISPLAY INVISIBLE (-8400 5925);
FORCEPROP 1 LASTPIN (-8450 5650) $PN 1
R 1
J 0
(-8462 5662);
DISPLAY 0.787234 (-8462 5662);
PAINT MONO (-8462 5662);
DISPLAY INVISIBLE (-8462 5662);
FORCEPROP 1 LASTPIN (-8450 5850) $PN 2
R 1
J 0
(-8462 5812);
DISPLAY 0.787234 (-8462 5812);
PAINT MONO (-8462 5812);
DISPLAY INVISIBLE (-8462 5812);
FORCEPROP 1 LAST WATTAGE 1/16W
J 0
(-8400 5750);
DISPLAY 0.489362 (-8400 5750);
PAINT SKYBLUE (-8400 5750);
FORCEPROP 1 LAST MATERIAL CHIP
J 0
(-8400 5700);
DISPLAY 0.489362 (-8400 5700);
PAINT SKYBLUE (-8400 5700);
FORCEPROP 1 LAST TOLERANCE 5%
J 0
(-8400 5800);
DISPLAY 0.489362 (-8400 5800);
PAINT SKYBLUE (-8400 5800);
FORCEPROP 1 LAST VALUE 0
J 2
(-8375 5850);
DISPLAY 0.489362 (-8375 5850);
PAINT SKYBLUE (-8375 5850);
FORCEPROP 1 LAST PART_NUMBER CS00002JB38
J 0
(-8400 5650);
DISPLAY 0.489362 (-8400 5650);
PAINT SKYBLUE (-8400 5650);
FORCEPROP 1 LAST PACK_TYPE 0402LF
J 0
(-8400 5600);
DISPLAY 0.489362 (-8400 5600);
PAINT SKYBLUE (-8400 5600);
FORCEPROP 2 LAST CDS_LIB pure_quanta
J 0
(-8450 5750);
DISPLAY INVISIBLE (-8450 5750);
FORCEPROP 1 LAST PATH I151
R 1
J 0
(-8600 5700);
DISPLAY 0.978723 (-8600 5700);
PAINT WHITE (-8600 5700);
DISPLAY INVISIBLE (-8600 5700);
FORCEADD Q_RES..2
(-1225 4275);
FORCEPROP 1 LAST LOCATION PR414
J 0
(-1180 4400);
DISPLAY 0.489362 (-1180 4400);
PAINT SKYBLUE (-1180 4400);
FORCEPROP 0 LAST $SEC 1
J 0
(-1175 4425);
DISPLAY 0.680851 (-1175 4425);
PAINT MONO (-1175 4425);
DISPLAY INVISIBLE (-1175 4425);
FORCEPROP 0 LAST CDS_SEC 1
J 0
(-1175 4425);
DISPLAY 1.021277 (-1175 4425);
DISPLAY INVISIBLE (-1175 4425);
FORCEPROP 1 LASTPIN (-1225 4375) $PN 1
J 0
(-1220 4337);
DISPLAY 0.787234 (-1220 4337);
PAINT MONO (-1220 4337);
DISPLAY INVISIBLE (-1220 4337);
FORCEPROP 1 LASTPIN (-1225 4175) $PN 2
J 0
(-1220 4185);
DISPLAY 0.787234 (-1220 4185);
PAINT MONO (-1220 4185);
DISPLAY INVISIBLE (-1220 4185);
FORCEPROP 1 LAST WATTAGE 1/16W
J 0
(-1185 4250);
DISPLAY 0.489362 (-1185 4250);
PAINT SKYBLUE (-1185 4250);
FORCEPROP 1 LAST MATERIAL CHIP
J 0
(-1185 4200);
DISPLAY 0.489362 (-1185 4200);
PAINT SKYBLUE (-1185 4200);
FORCEPROP 1 LAST TOLERANCE 1%
J 0
(-1180 4300);
DISPLAY 0.489362 (-1180 4300);
PAINT SKYBLUE (-1180 4300);
FORCEPROP 1 LAST VALUE 1K
J 0
(-1180 4350);
DISPLAY 0.489362 (-1180 4350);
PAINT SKYBLUE (-1180 4350);
FORCEPROP 1 LAST PART_NUMBER TMP_QCS21002FB24
J 0
(-1185 4150);
DISPLAY 0.489362 (-1185 4150);
PAINT SKYBLUE (-1185 4150);
FORCEPROP 1 LAST PACK_TYPE 0402LF
J 0
(-1185 4100);
DISPLAY 0.489362 (-1185 4100);
PAINT SKYBLUE (-1185 4100);
FORCEPROP 2 LAST CDS_LIB pure_quanta
J 0
(-1225 4275);
DISPLAY INVISIBLE (-1225 4275);
FORCEPROP 1 LAST PATH I152
J 0
(-1175 4450);
DISPLAY 0.978723 (-1175 4450);
PAINT WHITE (-1175 4450);
DISPLAY INVISIBLE (-1175 4450);
FORCEADD Q_CAPP..1
(-2100 2900);
FORCEPROP 1 LAST LOCATION PC800
J 0
(-2050 3000);
DISPLAY 0.489362 (-2050 3000);
PAINT SKYBLUE (-2050 3000);
FORCEPROP 0 LAST $SEC 1
J 0
(-2050 3025);
DISPLAY 0.680851 (-2050 3025);
PAINT MONO (-2050 3025);
DISPLAY INVISIBLE (-2050 3025);
FORCEPROP 0 LAST CDS_SEC 1
J 0
(-2050 3025);
DISPLAY 0.680851 (-2050 3025);
DISPLAY INVISIBLE (-2050 3025);
FORCEPROP 1 LASTPIN (-2100 3000) $PN 1
J 0
(-2090 2985);
DISPLAY 0.489362 (-2090 2985);
PAINT MONO (-2090 2985);
FORCEPROP 1 LASTPIN (-2100 2800) $PN 2
J 0
(-2090 2785);
DISPLAY 0.489362 (-2090 2785);
PAINT MONO (-2090 2785);
FORCEPROP 1 LAST MATERIAL SPCAP
J 0
(-2050 2800);
DISPLAY 0.489362 (-2050 2800);
PAINT SKYBLUE (-2050 2800);
FORCEPROP 1 LAST TOLERANCE 20%
J 0
(-2050 2900);
DISPLAY 0.489362 (-2050 2900);
PAINT SKYBLUE (-2050 2900);
FORCEPROP 1 LAST VALUE 470UF
J 0
(-2050 2950);
DISPLAY 0.489362 (-2050 2950);
PAINT SKYBLUE (-2050 2950);
FORCEPROP 1 LAST PART_NUMBER CH747LM8825
J 0
(-2050 2700);
DISPLAY 0.489362 (-2050 2700);
PAINT SKYBLUE (-2050 2700);
FORCEPROP 1 LAST VOLTAGE 2.5V
J 0
(-2050 2850);
DISPLAY 0.489362 (-2050 2850);
PAINT SKYBLUE (-2050 2850);
FORCEPROP 1 LAST PACK_TYPE SMLF
J 0
(-2050 2750);
DISPLAY 0.489362 (-2050 2750);
PAINT SKYBLUE (-2050 2750);
FORCEPROP 2 LAST CDS_LIB pure_quanta
J 0
(-2100 2900);
DISPLAY INVISIBLE (-2100 2900);
FORCEPROP 1 LAST PATH I153
J 0
(-2050 3050);
DISPLAY 0.978723 (-2050 3050);
DISPLAY INVISIBLE (-2050 3050);
FORCEADD Q_CAPP..1
(-725 2925);
FORCEPROP 1 LAST LOCATION PC801
J 0
(-675 3025);
DISPLAY 0.489362 (-675 3025);
PAINT SKYBLUE (-675 3025);
FORCEPROP 0 LAST $SEC 1
J 0
(-675 3050);
DISPLAY 0.680851 (-675 3050);
PAINT MONO (-675 3050);
DISPLAY INVISIBLE (-675 3050);
FORCEPROP 0 LAST CDS_SEC 1
J 0
(-675 3050);
DISPLAY 0.680851 (-675 3050);
DISPLAY INVISIBLE (-675 3050);
FORCEPROP 1 LASTPIN (-725 3025) $PN 1
J 0
(-715 3010);
DISPLAY 0.489362 (-715 3010);
PAINT MONO (-715 3010);
FORCEPROP 1 LASTPIN (-725 2825) $PN 2
J 0
(-715 2810);
DISPLAY 0.489362 (-715 2810);
PAINT MONO (-715 2810);
FORCEPROP 1 LAST MATERIAL OSCON
J 0
(-675 2825);
DISPLAY 0.489362 (-675 2825);
PAINT SKYBLUE (-675 2825);
FORCEPROP 1 LAST TOLERANCE 20%
J 0
(-675 2925);
DISPLAY 0.489362 (-675 2925);
PAINT SKYBLUE (-675 2925);
FORCEPROP 1 LAST VALUE 390UF
J 0
(-675 2975);
DISPLAY 0.489362 (-675 2975);
PAINT SKYBLUE (-675 2975);
FORCEPROP 1 LAST PART_NUMBER CC7390JMZ12
J 0
(-675 2725);
DISPLAY 0.489362 (-675 2725);
PAINT SKYBLUE (-675 2725);
FORCEPROP 1 LAST VOLTAGE 2.5V
J 0
(-675 2875);
DISPLAY 0.489362 (-675 2875);
PAINT SKYBLUE (-675 2875);
FORCEPROP 1 LAST PACK_TYPE SMLF
J 0
(-675 2775);
DISPLAY 0.489362 (-675 2775);
PAINT SKYBLUE (-675 2775);
FORCEPROP 2 LAST CDS_LIB pure_quanta
J 0
(-725 2925);
DISPLAY INVISIBLE (-725 2925);
FORCEPROP 1 LAST PATH I154
J 0
(-675 3075);
DISPLAY 0.978723 (-675 3075);
DISPLAY INVISIBLE (-675 3075);
FORCEADD Q_RES..1
(-4775 4825);
FORCEPROP 1 LAST LOCATION PR135
J 0
(-4825 4900);
DISPLAY 0.489362 (-4825 4900);
PAINT SKYBLUE (-4825 4900);
FORCEPROP 0 LAST $SEC 1
J 0
(-4750 4900);
DISPLAY 0.680851 (-4750 4900);
PAINT MONO (-4750 4900);
DISPLAY INVISIBLE (-4750 4900);
FORCEPROP 0 LAST CDS_SEC 1
J 0
(-4750 4900);
DISPLAY 1.021277 (-4750 4900);
DISPLAY INVISIBLE (-4750 4900);
FORCEPROP 1 LASTPIN (-4875 4825) $PN 1
J 0
(-4863 4837);
DISPLAY 0.489362 (-4863 4837);
PAINT MONO (-4863 4837);
FORCEPROP 1 LASTPIN (-4675 4825) $PN 2
J 0
(-4713 4837);
DISPLAY 0.489362 (-4713 4837);
PAINT MONO (-4713 4837);
FORCEPROP 1 LAST PACK_TYPE 0402LF
J 0
(-4675 4725);
DISPLAY 0.489362 (-4675 4725);
PAINT SKYBLUE (-4675 4725);
FORCEPROP 1 LAST TOLERANCE 1%
J 0
(-4675 4850);
DISPLAY 0.489362 (-4675 4850);
PAINT SKYBLUE (-4675 4850);
FORCEPROP 1 LAST MATERIAL CHIP
J 0
(-5025 4725);
DISPLAY 0.489362 (-5025 4725);
PAINT SKYBLUE (-5025 4725);
FORCEPROP 1 LAST WATTAGE 1/16W
J 0
(-4675 4775);
DISPLAY 0.489362 (-4675 4775);
PAINT SKYBLUE (-4675 4775);
FORCEPROP 1 LAST VALUE 4.7
J 2
(-4875 4850);
DISPLAY 0.489362 (-4875 4850);
PAINT SKYBLUE (-4875 4850);
FORCEPROP 1 LAST PART_NUMBER CS-4702FB19
J 0
(-5025 4775);
DISPLAY 0.489362 (-5025 4775);
PAINT SKYBLUE (-5025 4775);
FORCEPROP 1 LAST PATH I19
J 0
(-4825 4975);
DISPLAY 0.978723 (-4825 4975);
PAINT WHITE (-4825 4975);
DISPLAY INVISIBLE (-4825 4975);
FORCEPROP 2 LAST CDS_LIB pure_quanta
J 0
(-4775 4825);
DISPLAY INVISIBLE (-4775 4825);
FORCEADD UNIVERSAL_GND..1
(-5450 3750);
FORCEPROP 3 LASTPIN (-5450 3800) SIG_NAME GND\g
J 0
(-5440 3810);
DISPLAY 0.659574 (-5440 3810);
PAINT MONO (-5440 3810);
DISPLAY INVISIBLE (-5440 3810);
FORCEPROP 2 LAST CDS_LIB pure_quanta_power
J 0
(-5450 3750);
DISPLAY INVISIBLE (-5450 3750);
FORCEPROP 1 LAST PATH I2
J 0
(-5375 3750);
DISPLAY 0.872340 (-5375 3750);
PAINT AQUA (-5375 3750);
DISPLAY INVISIBLE (-5375 3750);
FORCEPROP 1 LAST HDL_POWER GND
J 1
(-5425 3675);
DISPLAY 0.872340 (-5425 3675);
PAINT GREEN (-5425 3675);
DISPLAY INVISIBLE (-5425 3675);
FORCEADD Q_CAP..1
(-5400 5375);
FORCEPROP 1 LAST LOCATION PC207_1
J 0
(-5350 5475);
DISPLAY 0.489362 (-5350 5475);
PAINT SKYBLUE (-5350 5475);
FORCEPROP 0 LAST $SEC 1
J 0
(-5350 5500);
DISPLAY 0.680851 (-5350 5500);
PAINT MONO (-5350 5500);
DISPLAY INVISIBLE (-5350 5500);
FORCEPROP 0 LAST CDS_SEC 1
J 0
(-5350 5500);
DISPLAY 1.021277 (-5350 5500);
DISPLAY INVISIBLE (-5350 5500);
FORCEPROP 1 LASTPIN (-5400 5475) $PN 1
J 0
(-5390 5455);
DISPLAY 0.489362 (-5390 5455);
PAINT MONO (-5390 5455);
FORCEPROP 1 LASTPIN (-5400 5275) $PN 2
J 0
(-5390 5255);
DISPLAY 0.489362 (-5390 5255);
PAINT MONO (-5390 5255);
FORCEPROP 1 LAST MATERIAL X6S
J 0
(-5350 5275);
DISPLAY 0.489362 (-5350 5275);
PAINT SKYBLUE (-5350 5275);
FORCEPROP 1 LAST TOLERANCE 10%
J 0
(-5350 5325);
DISPLAY 0.489362 (-5350 5325);
PAINT SKYBLUE (-5350 5325);
FORCEPROP 1 LAST VALUE 1UF
J 0
(-5350 5425);
DISPLAY 0.489362 (-5350 5425);
PAINT SKYBLUE (-5350 5425);
FORCEPROP 1 LAST PART_NUMBER CH5104KEB02
J 0
(-5350 5225);
DISPLAY 0.489362 (-5350 5225);
PAINT SKYBLUE (-5350 5225);
FORCEPROP 1 LAST VOLTAGE 25V
J 0
(-5350 5375);
DISPLAY 0.489362 (-5350 5375);
PAINT SKYBLUE (-5350 5375);
FORCEPROP 1 LAST PACK_TYPE C0402
J 0
(-5350 5175);
DISPLAY 0.489362 (-5350 5175);
PAINT SKYBLUE (-5350 5175);
FORCEPROP 2 LAST CDS_LIB pure_quanta
J 0
(-5400 5375);
DISPLAY INVISIBLE (-5400 5375);
FORCEPROP 1 LAST PATH I23
J 0
(-5350 5525);
DISPLAY 0.978723 (-5350 5525);
PAINT WHITE (-5350 5525);
DISPLAY INVISIBLE (-5350 5525);
FORCEADD Q_CAP..1
(-4775 5375);
FORCEPROP 1 LAST LOCATION PC211_1
J 0
(-4725 5475);
DISPLAY 0.489362 (-4725 5475);
PAINT SKYBLUE (-4725 5475);
FORCEPROP 0 LAST $SEC 1
J 0
(-4725 5500);
DISPLAY 0.680851 (-4725 5500);
PAINT MONO (-4725 5500);
DISPLAY INVISIBLE (-4725 5500);
FORCEPROP 0 LAST CDS_SEC 1
J 0
(-4725 5500);
DISPLAY 1.021277 (-4725 5500);
DISPLAY INVISIBLE (-4725 5500);
FORCEPROP 1 LASTPIN (-4775 5475) $PN 1
J 0
(-4765 5455);
DISPLAY 0.489362 (-4765 5455);
PAINT MONO (-4765 5455);
FORCEPROP 1 LASTPIN (-4775 5275) $PN 2
J 0
(-4765 5255);
DISPLAY 0.489362 (-4765 5255);
PAINT MONO (-4765 5255);
FORCEPROP 1 LAST MATERIAL X6S
J 0
(-4725 5275);
DISPLAY 0.489362 (-4725 5275);
PAINT SKYBLUE (-4725 5275);
FORCEPROP 1 LAST TOLERANCE 10%
J 0
(-4725 5325);
DISPLAY 0.489362 (-4725 5325);
PAINT SKYBLUE (-4725 5325);
FORCEPROP 1 LAST VALUE 10UF
J 0
(-4725 5425);
DISPLAY 0.489362 (-4725 5425);
PAINT SKYBLUE (-4725 5425);
FORCEPROP 1 LAST PART_NUMBER CH6104KEA00
J 0
(-4725 5225);
DISPLAY 0.489362 (-4725 5225);
PAINT SKYBLUE (-4725 5225);
FORCEPROP 1 LAST VOLTAGE 25V
J 0
(-4725 5375);
DISPLAY 0.489362 (-4725 5375);
PAINT SKYBLUE (-4725 5375);
FORCEPROP 1 LAST PACK_TYPE C0805
J 0
(-4725 5175);
DISPLAY 0.489362 (-4725 5175);
PAINT SKYBLUE (-4725 5175);
FORCEPROP 2 LAST CDS_LIB pure_quanta
J 0
(-4775 5375);
DISPLAY INVISIBLE (-4775 5375);
FORCEPROP 1 LAST PATH I24
J 0
(-4725 5525);
DISPLAY 0.978723 (-4725 5525);
PAINT WHITE (-4725 5525);
DISPLAY INVISIBLE (-4725 5525);
FORCEADD Q_CAP..1
(-4400 5375);
FORCEPROP 1 LAST LOCATION PC213_1
J 0
(-4350 5475);
DISPLAY 0.489362 (-4350 5475);
PAINT SKYBLUE (-4350 5475);
FORCEPROP 0 LAST $SEC 1
J 0
(-4350 5500);
DISPLAY 0.680851 (-4350 5500);
PAINT MONO (-4350 5500);
DISPLAY INVISIBLE (-4350 5500);
FORCEPROP 0 LAST CDS_SEC 1
J 0
(-4350 5500);
DISPLAY 1.021277 (-4350 5500);
DISPLAY INVISIBLE (-4350 5500);
FORCEPROP 1 LASTPIN (-4400 5475) $PN 1
J 0
(-4390 5455);
DISPLAY 0.489362 (-4390 5455);
PAINT MONO (-4390 5455);
FORCEPROP 1 LASTPIN (-4400 5275) $PN 2
J 0
(-4390 5255);
DISPLAY 0.489362 (-4390 5255);
PAINT MONO (-4390 5255);
FORCEPROP 1 LAST MATERIAL X6S
J 0
(-4350 5275);
DISPLAY 0.489362 (-4350 5275);
PAINT SKYBLUE (-4350 5275);
FORCEPROP 1 LAST TOLERANCE 10%
J 0
(-4350 5325);
DISPLAY 0.489362 (-4350 5325);
PAINT SKYBLUE (-4350 5325);
FORCEPROP 1 LAST VALUE 10UF
J 0
(-4350 5425);
DISPLAY 0.489362 (-4350 5425);
PAINT SKYBLUE (-4350 5425);
FORCEPROP 1 LAST PART_NUMBER CH6104KEA00
J 0
(-4350 5225);
DISPLAY 0.489362 (-4350 5225);
PAINT SKYBLUE (-4350 5225);
FORCEPROP 1 LAST VOLTAGE 25V
J 0
(-4350 5375);
DISPLAY 0.489362 (-4350 5375);
PAINT SKYBLUE (-4350 5375);
FORCEPROP 1 LAST PACK_TYPE C0805
J 0
(-4350 5175);
DISPLAY 0.489362 (-4350 5175);
PAINT SKYBLUE (-4350 5175);
FORCEPROP 2 LAST CDS_LIB pure_quanta
J 0
(-4400 5375);
DISPLAY INVISIBLE (-4400 5375);
FORCEPROP 1 LAST PATH I25
J 0
(-4350 5525);
DISPLAY 0.978723 (-4350 5525);
PAINT WHITE (-4350 5525);
DISPLAY INVISIBLE (-4350 5525);
FORCEADD Q_CAP..1
(-4100 5375);
FORCEPROP 1 LAST LOCATION PC215_1
J 0
(-4050 5475);
DISPLAY 0.489362 (-4050 5475);
PAINT SKYBLUE (-4050 5475);
FORCEPROP 0 LAST $SEC 1
J 0
(-4050 5500);
DISPLAY 0.680851 (-4050 5500);
PAINT MONO (-4050 5500);
DISPLAY INVISIBLE (-4050 5500);
FORCEPROP 0 LAST CDS_SEC 1
J 0
(-4050 5500);
DISPLAY 1.021277 (-4050 5500);
DISPLAY INVISIBLE (-4050 5500);
FORCEPROP 1 LASTPIN (-4100 5475) $PN 1
J 0
(-4090 5455);
DISPLAY 0.489362 (-4090 5455);
PAINT MONO (-4090 5455);
FORCEPROP 1 LASTPIN (-4100 5275) $PN 2
J 0
(-4090 5255);
DISPLAY 0.489362 (-4090 5255);
PAINT MONO (-4090 5255);
FORCEPROP 1 LAST MATERIAL X6S
J 0
(-4050 5275);
DISPLAY 0.489362 (-4050 5275);
PAINT SKYBLUE (-4050 5275);
FORCEPROP 1 LAST TOLERANCE 10%
J 0
(-4050 5325);
DISPLAY 0.489362 (-4050 5325);
PAINT SKYBLUE (-4050 5325);
FORCEPROP 1 LAST VALUE 10UF
J 0
(-4050 5425);
DISPLAY 0.489362 (-4050 5425);
PAINT SKYBLUE (-4050 5425);
FORCEPROP 1 LAST VOLTAGE 25V
J 0
(-4050 5375);
DISPLAY 0.489362 (-4050 5375);
PAINT SKYBLUE (-4050 5375);
FORCEPROP 1 LAST PACK_TYPE C0805
J 0
(-4050 5175);
DISPLAY 0.489362 (-4050 5175);
PAINT SKYBLUE (-4050 5175);
FORCEPROP 1 LAST PART_NUMBER CH6104KEA00
J 0
(-4050 5225);
DISPLAY 0.489362 (-4050 5225);
PAINT SKYBLUE (-4050 5225);
FORCEPROP 2 LAST CDS_LIB pure_quanta
J 0
(-4100 5375);
DISPLAY INVISIBLE (-4100 5375);
FORCEPROP 1 LAST PATH I26
J 0
(-4050 5525);
DISPLAY 0.978723 (-4050 5525);
PAINT WHITE (-4050 5525);
DISPLAY INVISIBLE (-4050 5525);
FORCEADD Q_CAPP..1
(-3350 5375);
FORCEPROP 1 LAST LOCATION PC220
J 0
(-3300 5475);
DISPLAY 0.489362 (-3300 5475);
PAINT SKYBLUE (-3300 5475);
FORCEPROP 0 LAST $SEC 1
J 0
(-3300 5500);
DISPLAY 0.680851 (-3300 5500);
PAINT MONO (-3300 5500);
DISPLAY INVISIBLE (-3300 5500);
FORCEPROP 0 LAST CDS_SEC 1
J 0
(-3300 5500);
DISPLAY 1.021277 (-3300 5500);
DISPLAY INVISIBLE (-3300 5500);
FORCEPROP 1 LASTPIN (-3350 5475) $PN 1
J 0
(-3340 5460);
DISPLAY 0.489362 (-3340 5460);
PAINT MONO (-3340 5460);
FORCEPROP 1 LASTPIN (-3350 5275) $PN 2
J 0
(-3340 5260);
DISPLAY 0.489362 (-3340 5260);
PAINT MONO (-3340 5260);
FORCEPROP 1 LAST MATERIAL OSCON
J 0
(-3300 5275);
DISPLAY 0.489362 (-3300 5275);
PAINT SKYBLUE (-3300 5275);
FORCEPROP 1 LAST TOLERANCE 20%
J 0
(-3300 5375);
DISPLAY 0.489362 (-3300 5375);
PAINT SKYBLUE (-3300 5375);
FORCEPROP 1 LAST VALUE 220UF
J 0
(-3300 5425);
DISPLAY 0.489362 (-3300 5425);
PAINT SKYBLUE (-3300 5425);
FORCEPROP 1 LAST PART_NUMBER CC72204MD02
J 0
(-3300 5175);
DISPLAY 0.489362 (-3300 5175);
PAINT SKYBLUE (-3300 5175);
FORCEPROP 1 LAST VOLTAGE 25V
J 0
(-3300 5325);
DISPLAY 0.489362 (-3300 5325);
PAINT SKYBLUE (-3300 5325);
FORCEPROP 1 LAST PACK_TYPE THLF
J 0
(-3300 5225);
DISPLAY 0.489362 (-3300 5225);
PAINT SKYBLUE (-3300 5225);
FORCEPROP 2 LAST CDS_LIB pure_quanta
J 0
(-3350 5375);
DISPLAY INVISIBLE (-3350 5375);
FORCEPROP 1 LAST PATH I27
J 0
(-3300 5525);
DISPLAY 0.978723 (-3300 5525);
DISPLAY INVISIBLE (-3300 5525);
FORCEADD Q_CAP..1
(-2325 4300);
FORCEPROP 1 LAST LOCATION PC222
J 0
(-2275 4400);
DISPLAY 0.489362 (-2275 4400);
PAINT SKYBLUE (-2275 4400);
FORCEPROP 0 LAST $SEC 1
J 0
(-2275 4425);
DISPLAY 0.680851 (-2275 4425);
PAINT MONO (-2275 4425);
DISPLAY INVISIBLE (-2275 4425);
FORCEPROP 0 LAST CDS_SEC 1
J 0
(-2275 4425);
DISPLAY 1.021277 (-2275 4425);
DISPLAY INVISIBLE (-2275 4425);
FORCEPROP 1 LASTPIN (-2325 4400) $PN 1
J 0
(-2315 4380);
DISPLAY 0.489362 (-2315 4380);
PAINT MONO (-2315 4380);
FORCEPROP 1 LASTPIN (-2325 4200) $PN 2
J 0
(-2315 4180);
DISPLAY 0.489362 (-2315 4180);
PAINT MONO (-2315 4180);
FORCEPROP 1 LAST MATERIAL X7R
J 0
(-2275 4200);
DISPLAY 0.489362 (-2275 4200);
PAINT SKYBLUE (-2275 4200);
FORCEPROP 1 LAST TOLERANCE 10%
J 0
(-2275 4250);
DISPLAY 0.489362 (-2275 4250);
PAINT SKYBLUE (-2275 4250);
FORCEPROP 1 LAST VALUE 0.1UF
J 0
(-2275 4350);
DISPLAY 0.489362 (-2275 4350);
PAINT SKYBLUE (-2275 4350);
FORCEPROP 1 LAST PART_NUMBER CH4104K1B00
J 0
(-2275 4150);
DISPLAY 0.489362 (-2275 4150);
PAINT SKYBLUE (-2275 4150);
FORCEPROP 1 LAST VOLTAGE 25V
J 0
(-2275 4300);
DISPLAY 0.489362 (-2275 4300);
PAINT SKYBLUE (-2275 4300);
FORCEPROP 1 LAST PACK_TYPE 0402
J 0
(-2275 4100);
DISPLAY 0.489362 (-2275 4100);
PAINT SKYBLUE (-2275 4100);
FORCEPROP 2 LAST CDS_LIB pure_quanta
J 0
(-2325 4300);
DISPLAY INVISIBLE (-2325 4300);
FORCEPROP 1 LAST PATH I29
J 0
(-2275 4450);
DISPLAY 0.978723 (-2275 4450);
PAINT WHITE (-2275 4450);
DISPLAY INVISIBLE (-2275 4450);
FORCEADD OFFPAGE..1
(-8125 4375);
FORCEPROP 2 LAST $XR1 184 
J 0
(-8527 4375);
DISPLAY 0.638298 (-8527 4375);
PAINT MONO (-8527 4375);
FORCEPROP 2 LAST $XR0 183 
J 0
(-8407 4375);
DISPLAY 0.638298 (-8407 4375);
PAINT MONO (-8407 4375);
FORCEPROP 1 LAST OFFPAGE TRUE
J 0
(-7800 4250);
DISPLAY 0.872340 (-7800 4250);
PAINT GREEN (-7800 4250);
DISPLAY INVISIBLE (-7800 4250);
FORCEPROP 2 LAST PATH I3
J 0
(-8075 4450);
DISPLAY 1.021277 (-8075 4450);
DISPLAY INVISIBLE (-8075 4450);
FORCEPROP 1 LAST COMMENT_BODY TRUE
J 0
(-8000 4275);
DISPLAY 0.872340 (-8000 4275);
PAINT GREEN (-8000 4275);
DISPLAY INVISIBLE (-8000 4275);
FORCEPROP 2 LAST CDS_LIB standard
J 0
(-8125 4375);
DISPLAY INVISIBLE (-8125 4375);
FORCEADD UNIVERSAL_GND..1
(-3925 5050);
FORCEPROP 3 LASTPIN (-3925 5100) SIG_NAME GND\g
J 0
(-3915 5110);
DISPLAY 0.659574 (-3915 5110);
PAINT MONO (-3915 5110);
DISPLAY INVISIBLE (-3915 5110);
FORCEPROP 2 LAST CDS_LIB pure_quanta_power
J 0
(-3925 5050);
DISPLAY INVISIBLE (-3925 5050);
FORCEPROP 1 LAST PATH I31
J 0
(-3850 5050);
DISPLAY 0.872340 (-3850 5050);
PAINT AQUA (-3850 5050);
DISPLAY INVISIBLE (-3850 5050);
FORCEPROP 1 LAST HDL_POWER GND
J 1
(-3900 4975);
DISPLAY 0.872340 (-3900 4975);
PAINT GREEN (-3900 4975);
DISPLAY INVISIBLE (-3900 4975);
FORCEADD Q_INDUCTOR..1
(-2925 5575);
FORCEPROP 1 LAST LOCATION PL24
J 0
(-3050 5735);
DISPLAY 0.489362 (-3050 5735);
PAINT SKYBLUE (-3050 5735);
FORCEPROP 0 LAST $SEC 1
J 0
(-3050 5850);
DISPLAY 0.680851 (-3050 5850);
PAINT MONO (-3050 5850);
DISPLAY INVISIBLE (-3050 5850);
FORCEPROP 0 LAST CDS_SEC 1
J 0
(-3050 5850);
DISPLAY 1.021277 (-3050 5850);
DISPLAY INVISIBLE (-3050 5850);
FORCEPROP 0 LASTPIN (-3025 5550) $PN 1
J 2
(-3035 5560);
DISPLAY 0.489362 (-3035 5560);
PAINT MONO (-3035 5560);
FORCEPROP 0 LASTPIN (-2825 5550) $PN 2
J 0
(-2815 5560);
DISPLAY 0.489362 (-2815 5560);
PAINT MONO (-2815 5560);
FORCEPROP 1 LAST MATERIAL IND
J 0
(-3050 5630);
DISPLAY 0.489362 (-3050 5630);
PAINT SKYBLUE (-3050 5630);
FORCEPROP 2 LAST VALUE 100NH/16A
J 0
(-3050 5825);
DISPLAY 0.489362 (-3050 5825);
PAINT SKYBLUE (-3050 5825);
FORCEPROP 1 LAST PART_NUMBER CV+10G0MZ12
J 0
(-3050 5685);
DISPLAY 0.489362 (-3050 5685);
PAINT SKYBLUE (-3050 5685);
FORCEPROP 2 LAST PACK_TYPE SMLF
J 0
(-3050 5775);
DISPLAY 0.489362 (-3050 5775);
PAINT SKYBLUE (-3050 5775);
FORCEPROP 1 LAST NEEDS_NO_SIZE TRUE
J 0
(-2925 5575);
DISPLAY 0.468085 (-2925 5575);
PAINT GREEN (-2925 5575);
DISPLAY INVISIBLE (-2925 5575);
FORCEPROP 2 LAST CDS_LIB pure_quanta
J 0
(-2925 5575);
DISPLAY INVISIBLE (-2925 5575);
FORCEPROP 1 LAST PATH I34
J 0
(-2850 5630);
DISPLAY 0.723404 (-2850 5630);
PAINT GREEN (-2850 5630);
DISPLAY INVISIBLE (-2850 5630);
FORCEADD VCC_CORE..1
(-2525 5750);
FORCEPROP 3 LASTPIN (-2525 5700) SIG_NAME P12V_STBY\g
J 0
(-2515 5710);
DISPLAY 0.659574 (-2515 5710);
PAINT MONO (-2515 5710);
DISPLAY INVISIBLE (-2515 5710);
FORCEPROP 1 LAST HDL_POWER P12V_STBY
J 1
(-2525 5800);
DISPLAY 0.489362 (-2525 5800);
PAINT GREEN (-2525 5800);
FORCEPROP 2 LAST CDS_LIB pure_quanta_power
J 0
(-2525 5750);
DISPLAY INVISIBLE (-2525 5750);
FORCEPROP 1 LAST PATH I35
J 0
(-2475 5775);
DISPLAY 0.872340 (-2475 5775);
PAINT AQUA (-2475 5775);
DISPLAY INVISIBLE (-2475 5775);
FORCEADD Q_CAP..1
(-1975 4300);
FORCEPROP 1 LAST LOCATION PC224_1
J 0
(-1925 4400);
DISPLAY 0.489362 (-1925 4400);
PAINT SKYBLUE (-1925 4400);
FORCEPROP 0 LAST $SEC 1
J 0
(-1925 4425);
DISPLAY 0.680851 (-1925 4425);
PAINT MONO (-1925 4425);
DISPLAY INVISIBLE (-1925 4425);
FORCEPROP 0 LAST CDS_SEC 1
J 0
(-1925 4425);
DISPLAY 1.021277 (-1925 4425);
DISPLAY INVISIBLE (-1925 4425);
FORCEPROP 1 LASTPIN (-1975 4400) $PN 1
J 0
(-1965 4380);
DISPLAY 0.489362 (-1965 4380);
PAINT MONO (-1965 4380);
FORCEPROP 1 LASTPIN (-1975 4200) $PN 2
J 0
(-1965 4180);
DISPLAY 0.489362 (-1965 4180);
PAINT MONO (-1965 4180);
FORCEPROP 1 LAST MATERIAL X6S
J 0
(-1925 4200);
DISPLAY 0.489362 (-1925 4200);
PAINT SKYBLUE (-1925 4200);
FORCEPROP 1 LAST TOLERANCE 20%
J 0
(-1925 4250);
DISPLAY 0.489362 (-1925 4250);
PAINT SKYBLUE (-1925 4250);
FORCEPROP 1 LAST VALUE 22UF
J 0
(-1925 4350);
DISPLAY 0.489362 (-1925 4350);
PAINT SKYBLUE (-1925 4350);
FORCEPROP 1 LAST PART_NUMBER TMP_QCH622KMEA01
J 0
(-1925 4150);
DISPLAY 0.489362 (-1925 4150);
PAINT SKYBLUE (-1925 4150);
FORCEPROP 1 LAST VOLTAGE 4V
J 0
(-1925 4300);
DISPLAY 0.489362 (-1925 4300);
PAINT SKYBLUE (-1925 4300);
FORCEPROP 1 LAST PACK_TYPE 0805
J 0
(-1925 4100);
DISPLAY 0.489362 (-1925 4100);
PAINT SKYBLUE (-1925 4100);
FORCEPROP 2 LAST CDS_LIB pure_quanta
J 0
(-1975 4300);
DISPLAY INVISIBLE (-1975 4300);
FORCEPROP 1 LAST PATH I37
J 0
(-1925 4450);
DISPLAY 0.978723 (-1925 4450);
PAINT WHITE (-1925 4450);
DISPLAY INVISIBLE (-1925 4450);
FORCEADD UNIVERSAL_GND..1
(-1225 3975);
FORCEPROP 3 LASTPIN (-1225 4025) SIG_NAME GND\g
J 0
(-1215 4035);
DISPLAY 0.659574 (-1215 4035);
PAINT MONO (-1215 4035);
DISPLAY INVISIBLE (-1215 4035);
FORCEPROP 2 LAST CDS_LIB pure_quanta_power
J 0
(-1225 3975);
DISPLAY INVISIBLE (-1225 3975);
FORCEPROP 1 LAST PATH I38
J 0
(-1150 3975);
DISPLAY 0.872340 (-1150 3975);
PAINT AQUA (-1150 3975);
DISPLAY INVISIBLE (-1150 3975);
FORCEPROP 1 LAST HDL_POWER GND
J 1
(-1200 3900);
DISPLAY 0.872340 (-1200 3900);
PAINT GREEN (-1200 3900);
DISPLAY INVISIBLE (-1200 3900);
FORCEADD Q_CAP..1
(-1550 4300);
FORCEPROP 1 LAST LOCATION PC227_1
J 0
(-1500 4400);
DISPLAY 0.489362 (-1500 4400);
PAINT SKYBLUE (-1500 4400);
FORCEPROP 0 LAST $SEC 1
J 0
(-1500 4425);
DISPLAY 0.680851 (-1500 4425);
PAINT MONO (-1500 4425);
DISPLAY INVISIBLE (-1500 4425);
FORCEPROP 0 LAST CDS_SEC 1
J 0
(-1500 4425);
DISPLAY 1.021277 (-1500 4425);
DISPLAY INVISIBLE (-1500 4425);
FORCEPROP 1 LASTPIN (-1550 4400) $PN 1
J 0
(-1540 4380);
DISPLAY 0.489362 (-1540 4380);
PAINT MONO (-1540 4380);
FORCEPROP 1 LASTPIN (-1550 4200) $PN 2
J 0
(-1540 4180);
DISPLAY 0.489362 (-1540 4180);
PAINT MONO (-1540 4180);
FORCEPROP 1 LAST MATERIAL X6S
J 0
(-1500 4200);
DISPLAY 0.489362 (-1500 4200);
PAINT SKYBLUE (-1500 4200);
FORCEPROP 1 LAST TOLERANCE 20%
J 0
(-1500 4250);
DISPLAY 0.489362 (-1500 4250);
PAINT SKYBLUE (-1500 4250);
FORCEPROP 1 LAST VALUE 22UF
J 0
(-1500 4350);
DISPLAY 0.489362 (-1500 4350);
PAINT SKYBLUE (-1500 4350);
FORCEPROP 1 LAST VOLTAGE 4V
J 0
(-1500 4300);
DISPLAY 0.489362 (-1500 4300);
PAINT SKYBLUE (-1500 4300);
FORCEPROP 1 LAST PACK_TYPE 0805
J 0
(-1500 4150);
DISPLAY 0.489362 (-1500 4150);
PAINT SKYBLUE (-1500 4150);
FORCEPROP 2 LAST CDS_LIB pure_quanta
J 0
(-1550 4300);
DISPLAY INVISIBLE (-1550 4300);
FORCEPROP 1 LAST PATH I39
J 0
(-1500 4450);
DISPLAY 0.978723 (-1500 4450);
PAINT WHITE (-1500 4450);
DISPLAY INVISIBLE (-1500 4450);
FORCEPROP 1 LAST PART_NUMBER TMP_QCH622KMEA01
J 0
(-1500 4150);
DISPLAY 0.489362 (-1500 4150);
PAINT SKYBLUE (-1500 4150);
DISPLAY INVISIBLE (-1500 4150);
FORCEADD Q_CAP..1
(-7900 4200);
FORCEPROP 1 LAST LOCATION PC201_1
J 0
(-7850 4300);
DISPLAY 0.489362 (-7850 4300);
PAINT SKYBLUE (-7850 4300);
FORCEPROP 0 LAST $SEC 1
J 0
(-7850 4325);
DISPLAY 0.680851 (-7850 4325);
PAINT MONO (-7850 4325);
DISPLAY INVISIBLE (-7850 4325);
FORCEPROP 0 LAST CDS_SEC 1
J 0
(-7850 4325);
DISPLAY 1.021277 (-7850 4325);
DISPLAY INVISIBLE (-7850 4325);
FORCEPROP 1 LASTPIN (-7900 4300) $PN 1
J 0
(-7890 4280);
DISPLAY 0.489362 (-7890 4280);
PAINT MONO (-7890 4280);
FORCEPROP 1 LASTPIN (-7900 4100) $PN 2
J 0
(-7890 4080);
DISPLAY 0.489362 (-7890 4080);
PAINT MONO (-7890 4080);
FORCEPROP 1 LAST MATERIAL X7R
J 0
(-7850 4100);
DISPLAY 0.489362 (-7850 4100);
PAINT SKYBLUE (-7850 4100);
FORCEPROP 1 LAST TOLERANCE 10%
J 0
(-7850 4150);
DISPLAY 0.489362 (-7850 4150);
PAINT SKYBLUE (-7850 4150);
FORCEPROP 1 LAST VALUE 0.1UF
J 0
(-7850 4250);
DISPLAY 0.489362 (-7850 4250);
PAINT SKYBLUE (-7850 4250);
FORCEPROP 1 LAST PART_NUMBER CH4104K1B00
J 0
(-7850 4050);
DISPLAY 0.489362 (-7850 4050);
PAINT SKYBLUE (-7850 4050);
FORCEPROP 1 LAST VOLTAGE 25V
J 0
(-7850 4200);
DISPLAY 0.489362 (-7850 4200);
PAINT SKYBLUE (-7850 4200);
FORCEPROP 1 LAST PACK_TYPE 0402
J 0
(-7850 4000);
DISPLAY 0.489362 (-7850 4000);
PAINT SKYBLUE (-7850 4000);
FORCEPROP 2 LAST CDS_LIB pure_quanta
J 0
(-7900 4200);
DISPLAY INVISIBLE (-7900 4200);
FORCEPROP 1 LAST PATH I4
J 0
(-7850 4350);
DISPLAY 0.978723 (-7850 4350);
PAINT WHITE (-7850 4350);
DISPLAY INVISIBLE (-7850 4350);
FORCEADD VCC_CORE..1
(-1225 4600);
FORCEPROP 3 LASTPIN (-1225 4550) SIG_NAME PVDD11_S3_P0\g
J 0
(-1215 4560);
DISPLAY 0.659574 (-1215 4560);
PAINT MONO (-1215 4560);
DISPLAY INVISIBLE (-1215 4560);
FORCEPROP 1 LAST HDL_POWER PVDD11_S3_P0
J 1
(-1225 4650);
DISPLAY 0.489362 (-1225 4650);
PAINT GREEN (-1225 4650);
FORCEPROP 2 LAST CDS_LIB pure_quanta_power
J 0
(-1225 4600);
DISPLAY INVISIBLE (-1225 4600);
FORCEPROP 1 LAST PATH I40
J 0
(-1175 4625);
DISPLAY 0.872340 (-1175 4625);
PAINT AQUA (-1175 4625);
DISPLAY INVISIBLE (-1175 4625);
FORCEADD Q_CAP..1
(-3950 4700);
FORCEPROP 1 LAST LOCATION PC217
J 0
(-3900 4825);
DISPLAY 0.489362 (-3900 4825);
PAINT SKYBLUE (-3900 4825);
FORCEPROP 0 LAST $SEC 1
J 0
(-3900 4850);
DISPLAY 0.680851 (-3900 4850);
PAINT MONO (-3900 4850);
DISPLAY INVISIBLE (-3900 4850);
FORCEPROP 0 LAST CDS_SEC 1
J 0
(-3900 4850);
DISPLAY 1.021277 (-3900 4850);
DISPLAY INVISIBLE (-3900 4850);
FORCEPROP 1 LASTPIN (-3950 4800) $PN 1
J 0
(-3940 4780);
DISPLAY 0.489362 (-3940 4780);
PAINT MONO (-3940 4780);
FORCEPROP 1 LASTPIN (-3950 4600) $PN 2
J 0
(-3940 4580);
DISPLAY 0.489362 (-3940 4580);
PAINT MONO (-3940 4580);
FORCEPROP 1 LAST MATERIAL X7R
J 0
(-3900 4625);
DISPLAY 0.489362 (-3900 4625);
PAINT SKYBLUE (-3900 4625);
FORCEPROP 1 LAST TOLERANCE 10%
J 0
(-3900 4675);
DISPLAY 0.489362 (-3900 4675);
PAINT SKYBLUE (-3900 4675);
FORCEPROP 1 LAST VALUE 0.22UF
J 0
(-3900 4775);
DISPLAY 0.489362 (-3900 4775);
PAINT SKYBLUE (-3900 4775);
FORCEPROP 1 LAST PART_NUMBER CH4223K1B00
J 0
(-3900 4575);
DISPLAY 0.489362 (-3900 4575);
PAINT SKYBLUE (-3900 4575);
FORCEPROP 1 LAST VOLTAGE 16V
J 0
(-3900 4725);
DISPLAY 0.489362 (-3900 4725);
PAINT SKYBLUE (-3900 4725);
FORCEPROP 1 LAST PACK_TYPE 0402
J 0
(-3900 4525);
DISPLAY 0.489362 (-3900 4525);
PAINT SKYBLUE (-3900 4525);
FORCEPROP 2 LAST CDS_LIB pure_quanta
J 0
(-3950 4700);
DISPLAY INVISIBLE (-3950 4700);
FORCEPROP 1 LAST PATH I43
J 0
(-3900 4850);
DISPLAY 0.978723 (-3900 4850);
PAINT WHITE (-3900 4850);
DISPLAY INVISIBLE (-3900 4850);
FORCEADD ISL99390FRZTR5935..1
(-6075 4475);
FORCEPROP 1 LAST LOCATION PU22
J 0
(-6375 5350);
DISPLAY 0.489362 (-6375 5350);
PAINT SKYBLUE (-6375 5350);
FORCEPROP 0 LAST $SEC 1
J 0
(-6375 5500);
DISPLAY 0.680851 (-6375 5500);
PAINT MONO (-6375 5500);
DISPLAY INVISIBLE (-6375 5500);
FORCEPROP 2 LAST CDS_SEC 1
J 0
(-6375 5500);
DISPLAY 1.021277 (-6375 5500);
DISPLAY INVISIBLE (-6375 5500);
FORCEPROP 0 LASTPIN (-5675 4025) $PN 2
J 0
(-5665 4035);
DISPLAY 0.489362 (-5665 4035);
PAINT MONO (-5665 4035);
FORCEPROP 0 LASTPIN (-5675 4825) $PN 33
J 0
(-5665 4835);
DISPLAY 0.489362 (-5665 4835);
PAINT MONO (-5665 4835);
FORCEPROP 0 LASTPIN (-6525 4225) $PN 31
J 2
(-6535 4235);
DISPLAY 0.489362 (-6535 4235);
PAINT MONO (-6535 4235);
FORCEPROP 0 LASTPIN (-6525 4625) $PN 35
J 2
(-6535 4635);
DISPLAY 0.489362 (-6535 4635);
PAINT MONO (-6535 4635);
FORCEPROP 0 LASTPIN (-5675 4175) $PN 6
J 0
(-5665 4185);
DISPLAY 0.489362 (-5665 4185);
PAINT MONO (-5665 4185);
FORCEPROP 0 LASTPIN (-5675 4125) $PN 41
J 0
(-5665 4135);
DISPLAY 0.489362 (-5665 4135);
PAINT MONO (-5665 4135);
FORCEPROP 0 LASTPIN (-6525 4475) $PN 38
J 2
(-6535 4485);
DISPLAY 0.489362 (-6535 4485);
PAINT MONO (-6535 4485);
FORCEPROP 0 LASTPIN (-6525 4175) $PN 37
J 2
(-6535 4185);
DISPLAY 0.489362 (-6535 4185);
PAINT MONO (-6535 4185);
FORCEPROP 0 LASTPIN (-5675 3975) $PN 5
J 0
(-5665 3985);
DISPLAY 0.489362 (-5665 3985);
PAINT MONO (-5665 3985);
FORCEPROP 0 LASTPIN (-5675 3925) $PN 7_9-20_24
J 0
(-5665 3935);
DISPLAY 0.489362 (-5665 3935);
PAINT MONO (-5665 3935);
FORCEPROP 0 LASTPIN (-5675 3875) $PN 40
J 0
(-5665 3885);
DISPLAY 0.489362 (-5665 3885);
PAINT MONO (-5665 3885);
FORCEPROP 0 LASTPIN (-5675 4575) $PN 32
J 0
(-5665 4585);
DISPLAY 0.489362 (-5665 4585);
PAINT MONO (-5665 4585);
FORCEPROP 0 LASTPIN (-6525 5125) $PN 4
J 2
(-6535 5135);
DISPLAY 0.489362 (-6535 5135);
PAINT MONO (-6535 5135);
FORCEPROP 0 LASTPIN (-6525 3875) $PN 34
J 2
(-6535 3885);
DISPLAY 0.489362 (-6535 3885);
PAINT MONO (-6535 3885);
FORCEPROP 0 LASTPIN (-6525 4375) $PN 39
J 2
(-6535 4385);
DISPLAY 0.489362 (-6535 4385);
PAINT MONO (-6535 4385);
FORCEPROP 0 LASTPIN (-5675 4475) $PN 10_19
J 0
(-5665 4485);
DISPLAY 0.489362 (-5665 4485);
PAINT MONO (-5665 4485);
FORCEPROP 0 LASTPIN (-6525 3975) $PN 36
J 2
(-6535 3985);
DISPLAY 0.489362 (-6535 3985);
PAINT MONO (-6535 3985);
FORCEPROP 0 LASTPIN (-6525 4825) $PN 3
J 2
(-6535 4835);
DISPLAY 0.489362 (-6535 4835);
PAINT MONO (-6535 4835);
FORCEPROP 0 LASTPIN (-5675 5125) $PN 25_29
J 0
(-5665 5135);
DISPLAY 0.489362 (-5665 5135);
PAINT MONO (-5665 5135);
FORCEPROP 0 LASTPIN (-5675 5075) $PN 30
J 0
(-5665 5085);
DISPLAY 0.489362 (-5665 5085);
PAINT MONO (-5665 5085);
FORCEPROP 0 LASTPIN (-5675 4225) $PN 1
J 0
(-5665 4235);
DISPLAY 0.489362 (-5665 4235);
PAINT MONO (-5665 4235);
FORCEPROP 2 LAST PART_TYPE SMLF
J 0
(-6375 5450);
DISPLAY 1.021277 (-6375 5450);
FORCEPROP 1 LAST MATERIAL IC
J 0
(-6375 5200);
DISPLAY 0.489362 (-6375 5200);
PAINT SKYBLUE (-6375 5200);
FORCEPROP 2 LAST VALUE ISL99390FRZ-TR5935
J 0
(-6375 5400);
DISPLAY 0.489362 (-6375 5400);
PAINT SKYBLUE (-6375 5400);
FORCEPROP 1 LAST PART_NUMBER AL099390004
J 0
(-6375 5275);
DISPLAY 0.489362 (-6375 5275);
PAINT SKYBLUE (-6375 5275);
FORCEPROP 1 LAST CDS_LMAN_SYM_OUTLINE -300,700,250,-650
J 0
(-6075 4475);
DISPLAY 0.468085 (-6075 4475);
PAINT GREEN (-6075 4475);
DISPLAY INVISIBLE (-6075 4475);
FORCEPROP 1 LAST NEEDS_NO_SIZE TRUE
J 0
(-6075 4475);
DISPLAY 0.723404 (-6075 4475);
PAINT GREEN (-6075 4475);
DISPLAY INVISIBLE (-6075 4475);
FORCEPROP 2 LAST CDS_LIB pure_quanta
J 0
(-6075 4475);
DISPLAY INVISIBLE (-6075 4475);
FORCEPROP 1 LAST PATH I44
J 0
(-6075 4475);
DISPLAY 0.723404 (-6075 4475);
PAINT GREEN (-6075 4475);
DISPLAY INVISIBLE (-6075 4475);
FORCEADD OFFPAGE..1
(-8075 1450);
FORCEPROP 2 LAST $XR1 184 
J 0
(-8447 1450);
DISPLAY 0.638298 (-8447 1450);
PAINT MONO (-8447 1450);
FORCEPROP 2 LAST $XR0 183 
J 0
(-8327 1450);
DISPLAY 0.638298 (-8327 1450);
PAINT MONO (-8327 1450);
FORCEPROP 2 LAST PATH I45
J 0
(-8025 1525);
DISPLAY 1.021277 (-8025 1525);
DISPLAY INVISIBLE (-8025 1525);
FORCEPROP 1 LAST OFFPAGE TRUE
J 0
(-7750 1325);
DISPLAY 0.872340 (-7750 1325);
PAINT GREEN (-7750 1325);
DISPLAY INVISIBLE (-7750 1325);
FORCEPROP 1 LAST COMMENT_BODY TRUE
J 0
(-7950 1350);
DISPLAY 0.872340 (-7950 1350);
PAINT GREEN (-7950 1350);
DISPLAY INVISIBLE (-7950 1350);
FORCEPROP 2 LAST CDS_LIB standard
J 0
(-8075 1450);
DISPLAY INVISIBLE (-8075 1450);
FORCEADD UNIVERSAL_GND..1
(-5450 825);
FORCEPROP 3 LASTPIN (-5450 875) SIG_NAME GND\g
J 0
(-5440 885);
DISPLAY 0.659574 (-5440 885);
PAINT MONO (-5440 885);
DISPLAY INVISIBLE (-5440 885);
FORCEPROP 2 LAST CDS_LIB pure_quanta_power
J 0
(-5450 825);
DISPLAY INVISIBLE (-5450 825);
FORCEPROP 1 LAST PATH I46
J 0
(-5375 825);
DISPLAY 0.872340 (-5375 825);
PAINT AQUA (-5375 825);
DISPLAY INVISIBLE (-5375 825);
FORCEPROP 1 LAST HDL_POWER GND
J 1
(-5425 750);
DISPLAY 0.872340 (-5425 750);
PAINT GREEN (-5425 750);
DISPLAY INVISIBLE (-5425 750);
FORCEADD OFFPAGE..1
(-7125 950);
FORCEPROP 2 LAST $XR0 183 
J 0
(-7407 950);
DISPLAY 0.638298 (-7407 950);
PAINT MONO (-7407 950);
FORCEPROP 2 LAST PATH I47
J 0
(-7075 1025);
DISPLAY 1.021277 (-7075 1025);
DISPLAY INVISIBLE (-7075 1025);
FORCEPROP 1 LAST COMMENT_BODY TRUE
J 0
(-7000 850);
DISPLAY 0.872340 (-7000 850);
PAINT GREEN (-7000 850);
DISPLAY INVISIBLE (-7000 850);
FORCEPROP 2 LAST CDS_LIB standard
J 2
(-7125 950);
DISPLAY INVISIBLE (-7125 950);
FORCEPROP 1 LAST OFFPAGE TRUE
J 0
(-6800 825);
DISPLAY 0.872340 (-6800 825);
PAINT GREEN (-6800 825);
DISPLAY INVISIBLE (-6800 825);
FORCEADD Q_CAP..1
(-7850 1275);
FORCEPROP 1 LAST LOCATION PC202_2
J 0
(-7800 1375);
DISPLAY 0.489362 (-7800 1375);
PAINT SKYBLUE (-7800 1375);
FORCEPROP 0 LAST $SEC 1
J 0
(-7800 1400);
DISPLAY 0.680851 (-7800 1400);
PAINT MONO (-7800 1400);
DISPLAY INVISIBLE (-7800 1400);
FORCEPROP 0 LAST CDS_SEC 1
J 0
(-7800 1400);
DISPLAY 1.021277 (-7800 1400);
DISPLAY INVISIBLE (-7800 1400);
FORCEPROP 1 LASTPIN (-7850 1375) $PN 1
J 0
(-7840 1355);
DISPLAY 0.489362 (-7840 1355);
PAINT MONO (-7840 1355);
FORCEPROP 1 LASTPIN (-7850 1175) $PN 2
J 0
(-7840 1155);
DISPLAY 0.489362 (-7840 1155);
PAINT MONO (-7840 1155);
FORCEPROP 1 LAST MATERIAL X7R
J 0
(-7800 1175);
DISPLAY 0.489362 (-7800 1175);
PAINT SKYBLUE (-7800 1175);
FORCEPROP 1 LAST TOLERANCE 10%
J 0
(-7800 1225);
DISPLAY 0.489362 (-7800 1225);
PAINT SKYBLUE (-7800 1225);
FORCEPROP 1 LAST VALUE 0.1UF
J 0
(-7800 1325);
DISPLAY 0.489362 (-7800 1325);
PAINT SKYBLUE (-7800 1325);
FORCEPROP 1 LAST PART_NUMBER CH4104K1B00
J 0
(-7800 1125);
DISPLAY 0.489362 (-7800 1125);
PAINT SKYBLUE (-7800 1125);
FORCEPROP 1 LAST VOLTAGE 25V
J 0
(-7800 1275);
DISPLAY 0.489362 (-7800 1275);
PAINT SKYBLUE (-7800 1275);
FORCEPROP 1 LAST PACK_TYPE 0402
J 0
(-7800 1075);
DISPLAY 0.489362 (-7800 1075);
PAINT SKYBLUE (-7800 1075);
FORCEPROP 2 LAST CDS_LIB pure_quanta
J 0
(-7850 1275);
DISPLAY INVISIBLE (-7850 1275);
FORCEPROP 1 LAST PATH I48
J 0
(-7800 1425);
DISPLAY 0.978723 (-7800 1425);
PAINT WHITE (-7800 1425);
DISPLAY INVISIBLE (-7800 1425);
FORCEADD UNIVERSAL_GND..1
(-7850 1000);
FORCEPROP 3 LASTPIN (-7850 1050) SIG_NAME GND\g
J 0
(-7840 1060);
DISPLAY 0.659574 (-7840 1060);
PAINT MONO (-7840 1060);
DISPLAY INVISIBLE (-7840 1060);
FORCEPROP 2 LAST CDS_LIB pure_quanta_power
J 0
(-7850 1000);
DISPLAY INVISIBLE (-7850 1000);
FORCEPROP 1 LAST PATH I49
J 0
(-7775 1000);
DISPLAY 0.872340 (-7775 1000);
PAINT AQUA (-7775 1000);
DISPLAY INVISIBLE (-7775 1000);
FORCEPROP 1 LAST HDL_POWER GND
J 1
(-7825 925);
DISPLAY 0.872340 (-7825 925);
PAINT GREEN (-7825 925);
DISPLAY INVISIBLE (-7825 925);
FORCEADD UNIVERSAL_GND..1
(-7900 3925);
FORCEPROP 3 LASTPIN (-7900 3975) SIG_NAME GND\g
J 0
(-7890 3985);
DISPLAY 0.659574 (-7890 3985);
PAINT MONO (-7890 3985);
DISPLAY INVISIBLE (-7890 3985);
FORCEPROP 2 LAST CDS_LIB pure_quanta_power
J 0
(-7900 3925);
DISPLAY INVISIBLE (-7900 3925);
FORCEPROP 1 LAST PATH I5
J 0
(-7825 3925);
DISPLAY 0.872340 (-7825 3925);
PAINT AQUA (-7825 3925);
DISPLAY INVISIBLE (-7825 3925);
FORCEPROP 1 LAST HDL_POWER GND
J 1
(-7875 3850);
DISPLAY 0.872340 (-7875 3850);
PAINT GREEN (-7875 3850);
DISPLAY INVISIBLE (-7875 3850);
FORCEADD UNIVERSAL_GND..1
(-7525 1075);
FORCEPROP 3 LASTPIN (-7525 1125) SIG_NAME GND\g
J 0
(-7515 1135);
DISPLAY 0.659574 (-7515 1135);
PAINT MONO (-7515 1135);
DISPLAY INVISIBLE (-7515 1135);
FORCEPROP 2 LAST CDS_LIB pure_quanta_power
J 0
(-7525 1075);
DISPLAY INVISIBLE (-7525 1075);
FORCEPROP 1 LAST PATH I50
J 0
(-7450 1075);
DISPLAY 0.872340 (-7450 1075);
PAINT AQUA (-7450 1075);
DISPLAY INVISIBLE (-7450 1075);
FORCEPROP 1 LAST HDL_POWER GND
J 1
(-7500 1000);
DISPLAY 0.872340 (-7500 1000);
PAINT GREEN (-7500 1000);
DISPLAY INVISIBLE (-7500 1000);
FORCEADD OFFPAGE..2
R 2
(-7150 1050);
FORCEPROP 2 LAST $XR1 183 
J 0
(-7435 1014);
DISPLAY 0.638298 (-7435 1014);
PAINT MONO (-7435 1014);
FORCEPROP 2 LAST $XR0 184 
J 0
(-7435 1050);
DISPLAY 0.638298 (-7435 1050);
PAINT MONO (-7435 1050);
FORCEPROP 2 LAST PATH I51
J 0
(-7100 1125);
DISPLAY 1.021277 (-7100 1125);
DISPLAY INVISIBLE (-7100 1125);
FORCEPROP 2 LAST CDS_LIB standard
J 0
(-7150 1050);
DISPLAY INVISIBLE (-7150 1050);
FORCEPROP 1 LAST COMMENT_BODY TRUE
J 2
(-7105 955);
DISPLAY 0.872340 (-7105 955);
PAINT GREEN (-7105 955);
DISPLAY INVISIBLE (-7105 955);
FORCEPROP 1 LAST OFFPAGE TRUE
J 2
(-7475 925);
DISPLAY 0.872340 (-7475 925);
PAINT GREEN (-7475 925);
DISPLAY INVISIBLE (-7475 925);
FORCEADD Q_RES..1
(-7200 1250);
FORCEPROP 1 LAST LOCATION PR134
J 0
(-7200 1300);
DISPLAY 0.489362 (-7200 1300);
PAINT SKYBLUE (-7200 1300);
FORCEPROP 0 LAST $SEC 1
J 0
(-7200 1325);
DISPLAY 0.680851 (-7200 1325);
PAINT MONO (-7200 1325);
DISPLAY INVISIBLE (-7200 1325);
FORCEPROP 0 LAST CDS_SEC 1
J 0
(-7200 1325);
DISPLAY 1.021277 (-7200 1325);
DISPLAY INVISIBLE (-7200 1325);
FORCEPROP 1 LASTPIN (-7300 1250) $PN 1
J 0
(-7288 1262);
DISPLAY 0.489362 (-7288 1262);
PAINT MONO (-7288 1262);
FORCEPROP 1 LASTPIN (-7100 1250) $PN 2
J 0
(-7138 1262);
DISPLAY 0.489362 (-7138 1262);
PAINT MONO (-7138 1262);
FORCEPROP 1 LAST WATTAGE 1/16W
J 0
(-7100 1150);
DISPLAY 0.489362 (-7100 1150);
PAINT SKYBLUE (-7100 1150);
FORCEPROP 1 LAST MATERIAL EMPTY
J 0
(-7500 1150);
DISPLAY 0.489362 (-7500 1150);
PAINT RED (-7500 1150);
FORCEPROP 1 LAST TOLERANCE 1%
J 0
(-7075 1275);
DISPLAY 0.489362 (-7075 1275);
PAINT SKYBLUE (-7075 1275);
FORCEPROP 1 LAST VALUE 4.87K
J 2
(-7275 1275);
DISPLAY 0.489362 (-7275 1275);
PAINT SKYBLUE (-7275 1275);
FORCEPROP 1 LAST PART_NUMBER CS24872FB07
J 0
(-7500 1200);
DISPLAY 0.489362 (-7500 1200);
PAINT SKYBLUE (-7500 1200);
FORCEPROP 1 LAST PACK_TYPE 0402LF
J 0
(-7100 1200);
DISPLAY 0.489362 (-7100 1200);
PAINT SKYBLUE (-7100 1200);
FORCEPROP 2 LAST CDS_LIB pure_quanta
J 0
(-7200 1250);
DISPLAY INVISIBLE (-7200 1250);
FORCEPROP 1 LAST PATH I52
J 0
(-7250 1400);
DISPLAY 0.978723 (-7250 1400);
PAINT WHITE (-7250 1400);
DISPLAY INVISIBLE (-7250 1400);
FORCEADD OFFPAGE..2
R 2
(-7175 1550);
FORCEPROP 2 LAST $XR0 183 
J 0
(-7460 1550);
DISPLAY 0.638298 (-7460 1550);
PAINT MONO (-7460 1550);
FORCEPROP 2 LAST PATH I55
J 0
(-7125 1625);
DISPLAY 1.021277 (-7125 1625);
DISPLAY INVISIBLE (-7125 1625);
FORCEPROP 1 LAST COMMENT_BODY TRUE
J 2
(-7130 1455);
DISPLAY 0.872340 (-7130 1455);
PAINT GREEN (-7130 1455);
DISPLAY INVISIBLE (-7130 1455);
FORCEPROP 2 LAST CDS_LIB standard
J 2
(-7175 1550);
DISPLAY INVISIBLE (-7175 1550);
FORCEPROP 1 LAST OFFPAGE TRUE
J 2
(-7500 1425);
DISPLAY 0.872340 (-7500 1425);
PAINT GREEN (-7500 1425);
DISPLAY INVISIBLE (-7500 1425);
FORCEADD UNIVERSAL_GND..1
(-7550 4000);
FORCEPROP 3 LASTPIN (-7550 4050) SIG_NAME GND\g
J 0
(-7540 4060);
DISPLAY 0.659574 (-7540 4060);
PAINT MONO (-7540 4060);
DISPLAY INVISIBLE (-7540 4060);
FORCEPROP 2 LAST CDS_LIB pure_quanta_power
J 0
(-7550 4000);
DISPLAY INVISIBLE (-7550 4000);
FORCEPROP 1 LAST PATH I6
J 0
(-7475 4000);
DISPLAY 0.872340 (-7475 4000);
PAINT AQUA (-7475 4000);
DISPLAY INVISIBLE (-7475 4000);
FORCEPROP 1 LAST HDL_POWER GND
J 1
(-7525 3925);
DISPLAY 0.872340 (-7525 3925);
PAINT GREEN (-7525 3925);
DISPLAY INVISIBLE (-7525 3925);
FORCEADD Q_RES..1
(-4700 1900);
FORCEPROP 1 LAST LOCATION PR136
J 0
(-4725 1950);
DISPLAY 0.489362 (-4725 1950);
PAINT SKYBLUE (-4725 1950);
FORCEPROP 0 LAST $SEC 1
J 0
(-4675 1975);
DISPLAY 0.680851 (-4675 1975);
PAINT MONO (-4675 1975);
DISPLAY INVISIBLE (-4675 1975);
FORCEPROP 0 LAST CDS_SEC 1
J 0
(-4675 1975);
DISPLAY 1.021277 (-4675 1975);
DISPLAY INVISIBLE (-4675 1975);
FORCEPROP 1 LASTPIN (-4800 1900) $PN 1
J 0
(-4788 1912);
DISPLAY 0.489362 (-4788 1912);
PAINT MONO (-4788 1912);
FORCEPROP 1 LASTPIN (-4600 1900) $PN 2
J 0
(-4638 1912);
DISPLAY 0.489362 (-4638 1912);
PAINT MONO (-4638 1912);
FORCEPROP 1 LAST PACK_TYPE 0402LF
J 0
(-4600 1800);
DISPLAY 0.489362 (-4600 1800);
PAINT SKYBLUE (-4600 1800);
FORCEPROP 1 LAST TOLERANCE 1%
J 0
(-4600 1925);
DISPLAY 0.489362 (-4600 1925);
PAINT SKYBLUE (-4600 1925);
FORCEPROP 1 LAST MATERIAL CHIP
J 0
(-4950 1800);
DISPLAY 0.489362 (-4950 1800);
PAINT SKYBLUE (-4950 1800);
FORCEPROP 1 LAST WATTAGE 1/16W
J 0
(-4600 1850);
DISPLAY 0.489362 (-4600 1850);
PAINT SKYBLUE (-4600 1850);
FORCEPROP 1 LAST VALUE 4.7
J 2
(-4800 1925);
DISPLAY 0.489362 (-4800 1925);
PAINT SKYBLUE (-4800 1925);
FORCEPROP 1 LAST PART_NUMBER CS-4702FB19
J 0
(-4950 1850);
DISPLAY 0.489362 (-4950 1850);
PAINT SKYBLUE (-4950 1850);
FORCEPROP 1 LAST PATH I63
J 0
(-4750 2050);
DISPLAY 0.978723 (-4750 2050);
PAINT WHITE (-4750 2050);
DISPLAY INVISIBLE (-4750 2050);
FORCEPROP 2 LAST CDS_LIB pure_quanta
J 0
(-4700 1900);
DISPLAY INVISIBLE (-4700 1900);
FORCEADD Q_CAP..1
(-3875 1775);
FORCEPROP 1 LAST LOCATION PC218
J 0
(-3825 1900);
DISPLAY 0.489362 (-3825 1900);
PAINT SKYBLUE (-3825 1900);
FORCEPROP 0 LAST $SEC 1
J 0
(-3825 1925);
DISPLAY 0.680851 (-3825 1925);
PAINT MONO (-3825 1925);
DISPLAY INVISIBLE (-3825 1925);
FORCEPROP 0 LAST CDS_SEC 1
J 0
(-3825 1925);
DISPLAY 1.021277 (-3825 1925);
DISPLAY INVISIBLE (-3825 1925);
FORCEPROP 1 LASTPIN (-3875 1875) $PN 1
J 0
(-3865 1855);
DISPLAY 0.489362 (-3865 1855);
PAINT MONO (-3865 1855);
FORCEPROP 1 LASTPIN (-3875 1675) $PN 2
J 0
(-3865 1655);
DISPLAY 0.489362 (-3865 1655);
PAINT MONO (-3865 1655);
FORCEPROP 1 LAST MATERIAL X7R
J 0
(-3825 1700);
DISPLAY 0.489362 (-3825 1700);
PAINT SKYBLUE (-3825 1700);
FORCEPROP 1 LAST TOLERANCE 10%
J 0
(-3825 1750);
DISPLAY 0.489362 (-3825 1750);
PAINT SKYBLUE (-3825 1750);
FORCEPROP 1 LAST VALUE 0.22UF
J 0
(-3825 1850);
DISPLAY 0.489362 (-3825 1850);
PAINT SKYBLUE (-3825 1850);
FORCEPROP 1 LAST PART_NUMBER CH4223K1B00
J 0
(-3825 1650);
DISPLAY 0.489362 (-3825 1650);
PAINT SKYBLUE (-3825 1650);
FORCEPROP 1 LAST VOLTAGE 16V
J 0
(-3825 1800);
DISPLAY 0.489362 (-3825 1800);
PAINT SKYBLUE (-3825 1800);
FORCEPROP 1 LAST PACK_TYPE 0402
J 0
(-3825 1600);
DISPLAY 0.489362 (-3825 1600);
PAINT SKYBLUE (-3825 1600);
FORCEPROP 2 LAST CDS_LIB pure_quanta
J 0
(-3875 1775);
DISPLAY INVISIBLE (-3875 1775);
FORCEPROP 1 LAST PATH I66
J 0
(-3825 1925);
DISPLAY 0.978723 (-3825 1925);
PAINT WHITE (-3825 1925);
DISPLAY INVISIBLE (-3825 1925);
FORCEADD Q_CAP..1
(-5350 2450);
FORCEPROP 1 LAST LOCATION PC208_2
J 0
(-5300 2550);
DISPLAY 0.489362 (-5300 2550);
PAINT SKYBLUE (-5300 2550);
FORCEPROP 0 LAST $SEC 1
J 0
(-5300 2575);
DISPLAY 0.680851 (-5300 2575);
PAINT MONO (-5300 2575);
DISPLAY INVISIBLE (-5300 2575);
FORCEPROP 0 LAST CDS_SEC 1
J 0
(-5300 2575);
DISPLAY 1.021277 (-5300 2575);
DISPLAY INVISIBLE (-5300 2575);
FORCEPROP 1 LASTPIN (-5350 2550) $PN 1
J 0
(-5340 2530);
DISPLAY 0.489362 (-5340 2530);
PAINT MONO (-5340 2530);
FORCEPROP 1 LASTPIN (-5350 2350) $PN 2
J 0
(-5340 2330);
DISPLAY 0.489362 (-5340 2330);
PAINT MONO (-5340 2330);
FORCEPROP 1 LAST MATERIAL X6S
J 0
(-5300 2350);
DISPLAY 0.489362 (-5300 2350);
PAINT SKYBLUE (-5300 2350);
FORCEPROP 1 LAST TOLERANCE 10%
J 0
(-5300 2400);
DISPLAY 0.489362 (-5300 2400);
PAINT SKYBLUE (-5300 2400);
FORCEPROP 1 LAST VALUE 1UF
J 0
(-5300 2500);
DISPLAY 0.489362 (-5300 2500);
PAINT SKYBLUE (-5300 2500);
FORCEPROP 1 LAST PART_NUMBER CH5104KEB02
J 0
(-5300 2300);
DISPLAY 0.489362 (-5300 2300);
PAINT SKYBLUE (-5300 2300);
FORCEPROP 1 LAST VOLTAGE 25V
J 0
(-5300 2450);
DISPLAY 0.489362 (-5300 2450);
PAINT SKYBLUE (-5300 2450);
FORCEPROP 1 LAST PACK_TYPE C0402
J 0
(-5300 2250);
DISPLAY 0.489362 (-5300 2250);
PAINT SKYBLUE (-5300 2250);
FORCEPROP 2 LAST CDS_LIB pure_quanta
J 0
(-5350 2450);
DISPLAY INVISIBLE (-5350 2450);
FORCEPROP 1 LAST PATH I67
J 0
(-5300 2600);
DISPLAY 0.978723 (-5300 2600);
PAINT WHITE (-5300 2600);
DISPLAY INVISIBLE (-5300 2600);
FORCEADD Q_CAP..1
(-4700 2450);
FORCEPROP 1 LAST LOCATION PC212_2
J 0
(-4650 2550);
DISPLAY 0.489362 (-4650 2550);
PAINT SKYBLUE (-4650 2550);
FORCEPROP 0 LAST $SEC 1
J 0
(-4650 2575);
DISPLAY 0.680851 (-4650 2575);
PAINT MONO (-4650 2575);
DISPLAY INVISIBLE (-4650 2575);
FORCEPROP 0 LAST CDS_SEC 1
J 0
(-4650 2575);
DISPLAY 1.021277 (-4650 2575);
DISPLAY INVISIBLE (-4650 2575);
FORCEPROP 1 LASTPIN (-4700 2550) $PN 1
J 0
(-4690 2530);
DISPLAY 0.489362 (-4690 2530);
PAINT MONO (-4690 2530);
FORCEPROP 1 LASTPIN (-4700 2350) $PN 2
J 0
(-4690 2330);
DISPLAY 0.489362 (-4690 2330);
PAINT MONO (-4690 2330);
FORCEPROP 1 LAST MATERIAL X6S
J 0
(-4650 2350);
DISPLAY 0.489362 (-4650 2350);
PAINT SKYBLUE (-4650 2350);
FORCEPROP 1 LAST TOLERANCE 10%
J 0
(-4650 2400);
DISPLAY 0.489362 (-4650 2400);
PAINT SKYBLUE (-4650 2400);
FORCEPROP 1 LAST VALUE 10UF
J 0
(-4650 2500);
DISPLAY 0.489362 (-4650 2500);
PAINT SKYBLUE (-4650 2500);
FORCEPROP 1 LAST PART_NUMBER CH6104KEA00
J 0
(-4650 2300);
DISPLAY 0.489362 (-4650 2300);
PAINT SKYBLUE (-4650 2300);
FORCEPROP 1 LAST VOLTAGE 25V
J 0
(-4650 2450);
DISPLAY 0.489362 (-4650 2450);
PAINT SKYBLUE (-4650 2450);
FORCEPROP 1 LAST PACK_TYPE C0805
J 0
(-4650 2250);
DISPLAY 0.489362 (-4650 2250);
PAINT SKYBLUE (-4650 2250);
FORCEPROP 2 LAST CDS_LIB pure_quanta
J 0
(-4700 2450);
DISPLAY INVISIBLE (-4700 2450);
FORCEPROP 1 LAST PATH I69
J 0
(-4650 2600);
DISPLAY 0.978723 (-4650 2600);
PAINT WHITE (-4650 2600);
DISPLAY INVISIBLE (-4650 2600);
FORCEADD OFFPAGE..2
R 2
(-7200 3975);
FORCEPROP 2 LAST $XR1 183 
J 0
(-7455 3939);
DISPLAY 0.638298 (-7455 3939);
PAINT MONO (-7455 3939);
FORCEPROP 2 LAST $XR0 184 
J 0
(-7455 3975);
DISPLAY 0.638298 (-7455 3975);
PAINT MONO (-7455 3975);
FORCEPROP 1 LAST COMMENT_BODY TRUE
J 2
(-7155 3880);
DISPLAY 0.872340 (-7155 3880);
PAINT GREEN (-7155 3880);
DISPLAY INVISIBLE (-7155 3880);
FORCEPROP 2 LAST PATH I7
J 0
(-7150 4050);
DISPLAY 1.021277 (-7150 4050);
DISPLAY INVISIBLE (-7150 4050);
FORCEPROP 2 LAST CDS_LIB standard
J 0
(-7200 3975);
DISPLAY INVISIBLE (-7200 3975);
FORCEPROP 1 LAST OFFPAGE TRUE
J 2
(-7525 3850);
DISPLAY 0.872340 (-7525 3850);
PAINT GREEN (-7525 3850);
DISPLAY INVISIBLE (-7525 3850);
FORCEADD Q_CAP..1
(-4400 2450);
FORCEPROP 1 LAST LOCATION PC214_2
J 0
(-4350 2550);
DISPLAY 0.489362 (-4350 2550);
PAINT SKYBLUE (-4350 2550);
FORCEPROP 0 LAST $SEC 1
J 0
(-4350 2575);
DISPLAY 0.680851 (-4350 2575);
PAINT MONO (-4350 2575);
DISPLAY INVISIBLE (-4350 2575);
FORCEPROP 0 LAST CDS_SEC 1
J 0
(-4350 2575);
DISPLAY 1.021277 (-4350 2575);
DISPLAY INVISIBLE (-4350 2575);
FORCEPROP 1 LASTPIN (-4400 2550) $PN 1
J 0
(-4390 2530);
DISPLAY 0.489362 (-4390 2530);
PAINT MONO (-4390 2530);
FORCEPROP 1 LASTPIN (-4400 2350) $PN 2
J 0
(-4390 2330);
DISPLAY 0.489362 (-4390 2330);
PAINT MONO (-4390 2330);
FORCEPROP 1 LAST MATERIAL X6S
J 0
(-4350 2350);
DISPLAY 0.489362 (-4350 2350);
PAINT SKYBLUE (-4350 2350);
FORCEPROP 1 LAST TOLERANCE 10%
J 0
(-4350 2400);
DISPLAY 0.489362 (-4350 2400);
PAINT SKYBLUE (-4350 2400);
FORCEPROP 1 LAST VALUE 10UF
J 0
(-4350 2500);
DISPLAY 0.489362 (-4350 2500);
PAINT SKYBLUE (-4350 2500);
FORCEPROP 1 LAST VOLTAGE 25V
J 0
(-4350 2450);
DISPLAY 0.489362 (-4350 2450);
PAINT SKYBLUE (-4350 2450);
FORCEPROP 1 LAST PART_NUMBER CH6104KEA00
J 0
(-4350 2300);
DISPLAY 0.489362 (-4350 2300);
PAINT SKYBLUE (-4350 2300);
FORCEPROP 1 LAST PACK_TYPE C0805
J 0
(-4350 2250);
DISPLAY 0.489362 (-4350 2250);
PAINT SKYBLUE (-4350 2250);
FORCEPROP 2 LAST CDS_LIB pure_quanta
J 0
(-4400 2450);
DISPLAY INVISIBLE (-4400 2450);
FORCEPROP 1 LAST PATH I70
J 0
(-4350 2600);
DISPLAY 0.978723 (-4350 2600);
PAINT WHITE (-4350 2600);
DISPLAY INVISIBLE (-4350 2600);
FORCEADD UNIVERSAL_GND..1
(-3725 2125);
FORCEPROP 3 LASTPIN (-3725 2175) SIG_NAME GND\g
J 0
(-3715 2185);
DISPLAY 0.659574 (-3715 2185);
PAINT MONO (-3715 2185);
DISPLAY INVISIBLE (-3715 2185);
FORCEPROP 2 LAST CDS_LIB pure_quanta_power
J 0
(-3725 2125);
DISPLAY INVISIBLE (-3725 2125);
FORCEPROP 1 LAST PATH I71
J 0
(-3650 2125);
DISPLAY 0.872340 (-3650 2125);
PAINT AQUA (-3650 2125);
DISPLAY INVISIBLE (-3650 2125);
FORCEPROP 1 LAST HDL_POWER GND
J 1
(-3700 2050);
DISPLAY 0.872340 (-3700 2050);
PAINT GREEN (-3700 2050);
DISPLAY INVISIBLE (-3700 2050);
FORCEADD VCC_CORE..1
(-3725 2725);
FORCEPROP 3 LASTPIN (-3725 2675) SIG_NAME SW_P12V_STBY_PVDD11_S3_P0_FLT\g
J 0
(-3715 2685);
DISPLAY 0.659574 (-3715 2685);
PAINT MONO (-3715 2685);
DISPLAY INVISIBLE (-3715 2685);
FORCEPROP 1 LAST HDL_POWER SW_P12V_STBY_PVDD11_S3_P0_FLT
J 1
(-3725 2775);
DISPLAY 0.489362 (-3725 2775);
PAINT GREEN (-3725 2775);
FORCEPROP 2 LAST CDS_LIB pure_quanta_power
J 0
(-3725 2725);
DISPLAY INVISIBLE (-3725 2725);
FORCEPROP 1 LAST PATH I73
J 0
(-3675 2750);
DISPLAY 0.872340 (-3675 2750);
PAINT AQUA (-3675 2750);
DISPLAY INVISIBLE (-3675 2750);
FORCEADD Q_CAP..1
(-2400 1375);
FORCEPROP 1 LAST LOCATION PC221_2
J 0
(-2350 1475);
DISPLAY 0.489362 (-2350 1475);
PAINT SKYBLUE (-2350 1475);
FORCEPROP 0 LAST $SEC 1
J 0
(-2350 1500);
DISPLAY 0.680851 (-2350 1500);
PAINT MONO (-2350 1500);
DISPLAY INVISIBLE (-2350 1500);
FORCEPROP 0 LAST CDS_SEC 1
J 0
(-2350 1500);
DISPLAY 1.021277 (-2350 1500);
DISPLAY INVISIBLE (-2350 1500);
FORCEPROP 1 LASTPIN (-2400 1475) $PN 1
J 0
(-2390 1455);
DISPLAY 0.489362 (-2390 1455);
PAINT MONO (-2390 1455);
FORCEPROP 1 LASTPIN (-2400 1275) $PN 2
J 0
(-2390 1255);
DISPLAY 0.489362 (-2390 1255);
PAINT MONO (-2390 1255);
FORCEPROP 1 LAST MATERIAL X6S
J 0
(-2350 1275);
DISPLAY 0.489362 (-2350 1275);
PAINT SKYBLUE (-2350 1275);
FORCEPROP 1 LAST TOLERANCE 20%
J 0
(-2350 1325);
DISPLAY 0.489362 (-2350 1325);
PAINT SKYBLUE (-2350 1325);
FORCEPROP 1 LAST VALUE 22UF
J 0
(-2350 1425);
DISPLAY 0.489362 (-2350 1425);
PAINT SKYBLUE (-2350 1425);
FORCEPROP 1 LAST PART_NUMBER TMP_QCH622KMEA01
J 0
(-2350 1225);
DISPLAY 0.489362 (-2350 1225);
PAINT SKYBLUE (-2350 1225);
FORCEPROP 1 LAST VOLTAGE 4V
J 0
(-2350 1375);
DISPLAY 0.489362 (-2350 1375);
PAINT SKYBLUE (-2350 1375);
FORCEPROP 1 LAST PACK_TYPE 0805
J 0
(-2350 1175);
DISPLAY 0.489362 (-2350 1175);
PAINT SKYBLUE (-2350 1175);
FORCEPROP 2 LAST CDS_LIB pure_quanta
J 0
(-2400 1375);
DISPLAY INVISIBLE (-2400 1375);
FORCEPROP 1 LAST PATH I79
J 0
(-2350 1525);
DISPLAY 0.978723 (-2350 1525);
PAINT WHITE (-2350 1525);
DISPLAY INVISIBLE (-2350 1525);
FORCEADD UNIVERSAL_GND..1
(-1975 1025);
FORCEPROP 3 LASTPIN (-1975 1075) SIG_NAME GND\g
J 0
(-1965 1085);
DISPLAY 0.659574 (-1965 1085);
PAINT MONO (-1965 1085);
DISPLAY INVISIBLE (-1965 1085);
FORCEPROP 2 LAST CDS_LIB pure_quanta_power
J 0
(-1975 1025);
DISPLAY INVISIBLE (-1975 1025);
FORCEPROP 1 LAST PATH I80
J 0
(-1900 1025);
DISPLAY 0.872340 (-1900 1025);
PAINT AQUA (-1900 1025);
DISPLAY INVISIBLE (-1900 1025);
FORCEPROP 1 LAST HDL_POWER GND
J 1
(-1950 950);
DISPLAY 0.872340 (-1950 950);
PAINT GREEN (-1950 950);
DISPLAY INVISIBLE (-1950 950);
FORCEADD Q_CAP..1
(-1975 1375);
FORCEPROP 1 LAST LOCATION PC225_2
J 0
(-1925 1475);
DISPLAY 0.489362 (-1925 1475);
PAINT SKYBLUE (-1925 1475);
FORCEPROP 0 LAST $SEC 1
J 0
(-1925 1500);
DISPLAY 0.680851 (-1925 1500);
PAINT MONO (-1925 1500);
DISPLAY INVISIBLE (-1925 1500);
FORCEPROP 0 LAST CDS_SEC 1
J 0
(-1925 1500);
DISPLAY 1.021277 (-1925 1500);
DISPLAY INVISIBLE (-1925 1500);
FORCEPROP 1 LASTPIN (-1975 1475) $PN 1
J 0
(-1965 1455);
DISPLAY 0.489362 (-1965 1455);
PAINT MONO (-1965 1455);
FORCEPROP 1 LASTPIN (-1975 1275) $PN 2
J 0
(-1965 1255);
DISPLAY 0.489362 (-1965 1255);
PAINT MONO (-1965 1255);
FORCEPROP 1 LAST MATERIAL X6S
J 0
(-1925 1275);
DISPLAY 0.489362 (-1925 1275);
PAINT SKYBLUE (-1925 1275);
FORCEPROP 1 LAST TOLERANCE 20%
J 0
(-1925 1325);
DISPLAY 0.489362 (-1925 1325);
PAINT SKYBLUE (-1925 1325);
FORCEPROP 1 LAST VALUE 22UF
J 0
(-1925 1425);
DISPLAY 0.489362 (-1925 1425);
PAINT SKYBLUE (-1925 1425);
FORCEPROP 1 LAST PART_NUMBER TMP_QCH622KMEA01
J 0
(-1925 1225);
DISPLAY 0.489362 (-1925 1225);
PAINT SKYBLUE (-1925 1225);
FORCEPROP 1 LAST VOLTAGE 4V
J 0
(-1925 1375);
DISPLAY 0.489362 (-1925 1375);
PAINT SKYBLUE (-1925 1375);
FORCEPROP 1 LAST PACK_TYPE 0805
J 0
(-1925 1175);
DISPLAY 0.489362 (-1925 1175);
PAINT SKYBLUE (-1925 1175);
FORCEPROP 2 LAST CDS_LIB pure_quanta
J 0
(-1975 1375);
DISPLAY INVISIBLE (-1975 1375);
FORCEPROP 1 LAST PATH I81
J 0
(-1925 1525);
DISPLAY 0.978723 (-1925 1525);
PAINT WHITE (-1925 1525);
DISPLAY INVISIBLE (-1925 1525);
FORCEADD VCC_CORE..1
(-1975 1700);
FORCEPROP 3 LASTPIN (-1975 1650) SIG_NAME PVDD11_S3_P0\g
J 0
(-1965 1660);
DISPLAY 0.659574 (-1965 1660);
PAINT MONO (-1965 1660);
DISPLAY INVISIBLE (-1965 1660);
FORCEPROP 1 LAST HDL_POWER PVDD11_S3_P0
J 1
(-1975 1750);
DISPLAY 0.489362 (-1975 1750);
PAINT GREEN (-1975 1750);
FORCEPROP 2 LAST CDS_LIB pure_quanta_power
J 0
(-1975 1700);
DISPLAY INVISIBLE (-1975 1700);
FORCEPROP 1 LAST PATH I82
J 0
(-1925 1725);
DISPLAY 0.872340 (-1925 1725);
PAINT AQUA (-1925 1725);
DISPLAY INVISIBLE (-1925 1725);
FORCEADD ISL99390FRZTR5935..1
(-6025 1550);
FORCEPROP 1 LAST LOCATION PU23
J 0
(-6325 2425);
DISPLAY 0.489362 (-6325 2425);
PAINT SKYBLUE (-6325 2425);
FORCEPROP 0 LAST $SEC 1
J 0
(-6325 2575);
DISPLAY 0.680851 (-6325 2575);
PAINT MONO (-6325 2575);
DISPLAY INVISIBLE (-6325 2575);
FORCEPROP 2 LAST CDS_SEC 1
J 0
(-6325 2575);
DISPLAY 1.021277 (-6325 2575);
DISPLAY INVISIBLE (-6325 2575);
FORCEPROP 0 LASTPIN (-5625 1100) $PN 2
J 0
(-5615 1110);
DISPLAY 0.489362 (-5615 1110);
PAINT MONO (-5615 1110);
FORCEPROP 0 LASTPIN (-5625 1900) $PN 33
J 0
(-5615 1910);
DISPLAY 0.489362 (-5615 1910);
PAINT MONO (-5615 1910);
FORCEPROP 0 LASTPIN (-6475 1300) $PN 31
J 2
(-6485 1310);
DISPLAY 0.489362 (-6485 1310);
PAINT MONO (-6485 1310);
FORCEPROP 0 LASTPIN (-6475 1700) $PN 35
J 2
(-6485 1710);
DISPLAY 0.489362 (-6485 1710);
PAINT MONO (-6485 1710);
FORCEPROP 0 LASTPIN (-5625 1250) $PN 6
J 0
(-5615 1260);
DISPLAY 0.489362 (-5615 1260);
PAINT MONO (-5615 1260);
FORCEPROP 0 LASTPIN (-5625 1200) $PN 41
J 0
(-5615 1210);
DISPLAY 0.489362 (-5615 1210);
PAINT MONO (-5615 1210);
FORCEPROP 0 LASTPIN (-6475 1550) $PN 38
J 2
(-6485 1560);
DISPLAY 0.489362 (-6485 1560);
PAINT MONO (-6485 1560);
FORCEPROP 0 LASTPIN (-6475 1250) $PN 37
J 2
(-6485 1260);
DISPLAY 0.489362 (-6485 1260);
PAINT MONO (-6485 1260);
FORCEPROP 0 LASTPIN (-5625 1050) $PN 5
J 0
(-5615 1060);
DISPLAY 0.489362 (-5615 1060);
PAINT MONO (-5615 1060);
FORCEPROP 0 LASTPIN (-5625 1000) $PN 7_9-20_24
J 0
(-5615 1010);
DISPLAY 0.489362 (-5615 1010);
PAINT MONO (-5615 1010);
FORCEPROP 0 LASTPIN (-5625 950) $PN 40
J 0
(-5615 960);
DISPLAY 0.489362 (-5615 960);
PAINT MONO (-5615 960);
FORCEPROP 0 LASTPIN (-5625 1650) $PN 32
J 0
(-5615 1660);
DISPLAY 0.489362 (-5615 1660);
PAINT MONO (-5615 1660);
FORCEPROP 0 LASTPIN (-6475 2200) $PN 4
J 2
(-6485 2210);
DISPLAY 0.489362 (-6485 2210);
PAINT MONO (-6485 2210);
FORCEPROP 0 LASTPIN (-6475 950) $PN 34
J 2
(-6485 960);
DISPLAY 0.489362 (-6485 960);
PAINT MONO (-6485 960);
FORCEPROP 0 LASTPIN (-6475 1450) $PN 39
J 2
(-6485 1460);
DISPLAY 0.489362 (-6485 1460);
PAINT MONO (-6485 1460);
FORCEPROP 0 LASTPIN (-5625 1550) $PN 10_19
J 0
(-5615 1560);
DISPLAY 0.489362 (-5615 1560);
PAINT MONO (-5615 1560);
FORCEPROP 0 LASTPIN (-6475 1050) $PN 36
J 2
(-6485 1060);
DISPLAY 0.489362 (-6485 1060);
PAINT MONO (-6485 1060);
FORCEPROP 0 LASTPIN (-6475 1900) $PN 3
J 2
(-6485 1910);
DISPLAY 0.489362 (-6485 1910);
PAINT MONO (-6485 1910);
FORCEPROP 0 LASTPIN (-5625 2200) $PN 25_29
J 0
(-5615 2210);
DISPLAY 0.489362 (-5615 2210);
PAINT MONO (-5615 2210);
FORCEPROP 0 LASTPIN (-5625 2150) $PN 30
J 0
(-5615 2160);
DISPLAY 0.489362 (-5615 2160);
PAINT MONO (-5615 2160);
FORCEPROP 0 LASTPIN (-5625 1300) $PN 1
J 0
(-5615 1310);
DISPLAY 0.489362 (-5615 1310);
PAINT MONO (-5615 1310);
FORCEPROP 2 LAST PART_TYPE SMLF
J 0
(-6325 2525);
DISPLAY 1.021277 (-6325 2525);
FORCEPROP 1 LAST MATERIAL IC
J 0
(-6325 2275);
DISPLAY 0.489362 (-6325 2275);
PAINT SKYBLUE (-6325 2275);
FORCEPROP 2 LAST VALUE ISL99390FRZ-TR5935
J 0
(-6325 2475);
DISPLAY 0.489362 (-6325 2475);
PAINT SKYBLUE (-6325 2475);
FORCEPROP 1 LAST PART_NUMBER AL099390004
J 0
(-6325 2350);
DISPLAY 0.489362 (-6325 2350);
PAINT SKYBLUE (-6325 2350);
FORCEPROP 1 LAST CDS_LMAN_SYM_OUTLINE -300,700,250,-650
J 0
(-6025 1550);
DISPLAY 0.468085 (-6025 1550);
PAINT GREEN (-6025 1550);
DISPLAY INVISIBLE (-6025 1550);
FORCEPROP 1 LAST NEEDS_NO_SIZE TRUE
J 0
(-6025 1550);
DISPLAY 0.723404 (-6025 1550);
PAINT GREEN (-6025 1550);
DISPLAY INVISIBLE (-6025 1550);
FORCEPROP 2 LAST CDS_LIB pure_quanta
J 0
(-6025 1550);
DISPLAY INVISIBLE (-6025 1550);
FORCEPROP 1 LAST PATH I84
J 0
(-6025 1550);
DISPLAY 0.723404 (-6025 1550);
PAINT GREEN (-6025 1550);
DISPLAY INVISIBLE (-6025 1550);
FORCEADD UNIVERSAL_GND..1
(-2750 2575);
FORCEPROP 3 LASTPIN (-2750 2625) SIG_NAME GND\g
J 0
(-2740 2635);
DISPLAY 0.659574 (-2740 2635);
PAINT MONO (-2740 2635);
DISPLAY INVISIBLE (-2740 2635);
FORCEPROP 2 LAST CDS_LIB pure_quanta_power
J 0
(-2750 2575);
DISPLAY INVISIBLE (-2750 2575);
FORCEPROP 1 LAST PATH I90
J 0
(-2675 2575);
DISPLAY 0.872340 (-2675 2575);
PAINT AQUA (-2675 2575);
DISPLAY INVISIBLE (-2675 2575);
FORCEPROP 1 LAST HDL_POWER GND
J 1
(-2725 2500);
DISPLAY 0.872340 (-2725 2500);
PAINT GREEN (-2725 2500);
DISPLAY INVISIBLE (-2725 2500);
FORCEADD VCC_CORE..1
(-2750 3150);
FORCEPROP 3 LASTPIN (-2750 3100) SIG_NAME PVDD11_S3_P0\g
J 0
(-2740 3110);
DISPLAY 0.659574 (-2740 3110);
PAINT MONO (-2740 3110);
DISPLAY INVISIBLE (-2740 3110);
FORCEPROP 1 LAST HDL_POWER PVDD11_S3_P0
J 1
(-2750 3200);
DISPLAY 0.489362 (-2750 3200);
PAINT GREEN (-2750 3200);
FORCEPROP 2 LAST CDS_LIB pure_quanta_power
J 0
(-2750 3150);
DISPLAY INVISIBLE (-2750 3150);
FORCEPROP 1 LAST PATH I93
J 0
(-2700 3175);
DISPLAY 0.872340 (-2700 3175);
PAINT AQUA (-2700 3175);
DISPLAY INVISIBLE (-2700 3175);
FORCEADD Q_CAPP..1
(-2750 2900);
FORCEPROP 1 LAST LOCATION PC223
J 0
(-2700 3000);
DISPLAY 0.489362 (-2700 3000);
PAINT SKYBLUE (-2700 3000);
FORCEPROP 0 LAST $SEC 1
J 0
(-2700 3025);
DISPLAY 0.680851 (-2700 3025);
PAINT MONO (-2700 3025);
DISPLAY INVISIBLE (-2700 3025);
FORCEPROP 0 LAST CDS_SEC 1
J 0
(-2700 3025);
DISPLAY 1.021277 (-2700 3025);
DISPLAY INVISIBLE (-2700 3025);
FORCEPROP 1 LASTPIN (-2750 3000) $PN 1
J 0
(-2740 2985);
DISPLAY 0.489362 (-2740 2985);
PAINT MONO (-2740 2985);
FORCEPROP 1 LASTPIN (-2750 2800) $PN 2
J 0
(-2740 2785);
DISPLAY 0.489362 (-2740 2785);
PAINT MONO (-2740 2785);
FORCEPROP 1 LAST MATERIAL SPCAP
J 0
(-2700 2800);
DISPLAY 0.489362 (-2700 2800);
PAINT SKYBLUE (-2700 2800);
FORCEPROP 1 LAST TOLERANCE 20%
J 0
(-2700 2900);
DISPLAY 0.489362 (-2700 2900);
PAINT SKYBLUE (-2700 2900);
FORCEPROP 1 LAST VALUE 470UF
J 0
(-2700 2950);
DISPLAY 0.489362 (-2700 2950);
PAINT SKYBLUE (-2700 2950);
FORCEPROP 1 LAST PART_NUMBER CH747LM8825
J 0
(-2700 2700);
DISPLAY 0.489362 (-2700 2700);
PAINT SKYBLUE (-2700 2700);
FORCEPROP 1 LAST VOLTAGE 2.5V
J 0
(-2700 2850);
DISPLAY 0.489362 (-2700 2850);
PAINT SKYBLUE (-2700 2850);
FORCEPROP 1 LAST PACK_TYPE SMLF
J 0
(-2700 2750);
DISPLAY 0.489362 (-2700 2750);
PAINT SKYBLUE (-2700 2750);
FORCEPROP 2 LAST CDS_LIB pure_quanta
J 0
(-2750 2900);
DISPLAY INVISIBLE (-2750 2900);
FORCEPROP 1 LAST PATH I98
J 0
(-2700 3050);
DISPLAY 0.978723 (-2700 3050);
DISPLAY INVISIBLE (-2700 3050);
FORCEADD DNS..1
(-8075 5750);
PAINT RED (-8075 5750);
FORCEPROP 2 LAST CDS_LIB mstr_misc
J 0
(-8075 5750);
DISPLAY INVISIBLE (-8075 5750);
FORCEPROP 1 LAST COMMENT_BODY TRUE
R 1
J 0
(-8000 5525);
DISPLAY 0.872340 (-8000 5525);
PAINT GREEN (-8000 5525);
DISPLAY INVISIBLE (-8000 5525);
FORCEADD DNS..1
(-4600 1350);
PAINT RED (-4600 1350);
FORCEPROP 2 LAST CDS_LIB mstr_misc
J 0
(-4600 1350);
DISPLAY INVISIBLE (-4600 1350);
FORCEPROP 1 LAST COMMENT_BODY TRUE
R 1
J 0
(-4525 1125);
DISPLAY 0.872340 (-4525 1125);
PAINT GREEN (-4525 1125);
DISPLAY INVISIBLE (-4525 1125);
FORCEADD DNS..1
(-7225 1250);
PAINT RED (-7225 1250);
FORCEPROP 2 LAST CDS_LIB mstr_misc
J 0
(-7225 1250);
DISPLAY INVISIBLE (-7225 1250);
FORCEPROP 1 LAST COMMENT_BODY TRUE
R 1
J 0
(-7150 1025);
DISPLAY 0.872340 (-7150 1025);
PAINT GREEN (-7150 1025);
DISPLAY INVISIBLE (-7150 1025);
FORCEADD DNS..1
(-4600 875);
PAINT RED (-4600 875);
FORCEPROP 2 LAST CDS_LIB mstr_misc
J 0
(-4600 875);
DISPLAY INVISIBLE (-4600 875);
FORCEPROP 1 LAST COMMENT_BODY TRUE
R 1
J 0
(-4525 650);
DISPLAY 0.872340 (-4525 650);
PAINT GREEN (-4525 650);
DISPLAY INVISIBLE (-4525 650);
FORCEADD DNS..1
(-7225 4150);
PAINT RED (-7225 4150);
FORCEPROP 2 LAST CDS_LIB mstr_misc
J 0
(-7225 4150);
DISPLAY INVISIBLE (-7225 4150);
FORCEPROP 1 LAST COMMENT_BODY TRUE
R 1
J 0
(-7150 3925);
DISPLAY 0.872340 (-7150 3925);
PAINT GREEN (-7150 3925);
DISPLAY INVISIBLE (-7150 3925);
FORCEADD DNS..1
(-4700 3800);
PAINT RED (-4700 3800);
FORCEPROP 2 LAST CDS_LIB mstr_misc
J 0
(-4700 3800);
DISPLAY INVISIBLE (-4700 3800);
FORCEPROP 1 LAST COMMENT_BODY TRUE
R 1
J 0
(-4625 3575);
DISPLAY 0.872340 (-4625 3575);
PAINT GREEN (-4625 3575);
DISPLAY INVISIBLE (-4625 3575);
FORCEADD DNS..1
(-4700 4275);
PAINT RED (-4700 4275);
FORCEPROP 2 LAST CDS_LIB mstr_misc
J 0
(-4700 4275);
DISPLAY INVISIBLE (-4700 4275);
FORCEPROP 1 LAST COMMENT_BODY TRUE
R 1
J 0
(-4625 4050);
DISPLAY 0.872340 (-4625 4050);
PAINT GREEN (-4625 4050);
DISPLAY INVISIBLE (-4625 4050);
FORCEADD QUANTA_TITLE_BLOCK_C..1
(-100 -475);
FORCEPROP 0 LAST CDS_CON_LAST_MODIFIED Fri Mar 11 14:53:31 2022
J 0
(-1985 -460);
DISPLAY INVISIBLE (-1985 -460);
FORCEPROP 1 LAST CUSTOM_TXT_CDS <CON_LAST_MODIFIED>
J 0
(-1985 -460);
DISPLAY 0.978723 (-1985 -460);
FORCEPROP 2 LAST CUSTOM_TXT_CDS <XR_PAGE_TITLE>
J 0
(-7990 4775);
DISPLAY 0.638298 (-7990 4775);
PAINT PINK (-7990 4775);
DISPLAY INVISIBLE (-7990 4775);
FORCEPROP 1 LAST CUSTOM_TXT_CDS <NAME_2>
J 0
(-3275 -425);
FORCEPROP 1 LAST CUSTOM_TXT_CDS <NAME_1>
J 0
(-3275 -300);
FORCEPROP 1 LAST CUSTOM_TXT_CDS <Q_NUMBER>
J 0
(-1503 -372);
DISPLAY 1.212766 (-1503 -372);
FORCEPROP 1 LAST CUSTOM_TXT_CDS <Q_PROJ>
J 0
(-2482 -373);
DISPLAY 1.212766 (-2482 -373);
FORCEPROP 1 LAST CUSTOM_TXT_CDS <Q_REV>
J 0
(-284 -372);
DISPLAY 1.212766 (-284 -372);
FORCEPROP 1 LAST CUSTOM_TXT_CDS <CON_PAGE_NUM> OF <CON_TOTAL_PAGES>
J 0
(-546 -457);
DISPLAY 0.978723 (-546 -457);
FORCEPROP 1 LAST Q_DEPT BU9
J 1
(-3863 -426);
DISPLAY 1.957447 (-3863 -426);
PAINT GREEN (-3863 -426);
FORCEPROP 1 LAST Q_TITLE PVDD11_S3_P0 VR PHASE 1&2
J 0
(-9400 -425);
DISPLAY 2.446809 (-9400 -425);
PAINT GREEN (-9400 -425);
FORCEPROP 1 LAST CDS_LMAN_SYM_OUTLINE -9475,6775,100,-125
J 0
(-100 -475);
DISPLAY 0.468085 (-100 -475);
PAINT GREEN (-100 -475);
DISPLAY INVISIBLE (-100 -475);
FORCEPROP 2 LAST CDS_LIB pure_quanta
J 0
(-100 -475);
DISPLAY INVISIBLE (-100 -475);
FORCEPROP 2 LAST PAGE_BORDER TRUE
J 0
(-7990 4775);
DISPLAY 0.638298 (-7990 4775);
PAINT PINK (-7990 4775);
DISPLAY INVISIBLE (-7990 4775);
FORCEPROP 1 LAST COMMENT_BODY TRUE
J 0
(-88 -488);
DISPLAY 0.978723 (-88 -488);
PAINT GREEN (-88 -488);
DISPLAY INVISIBLE (-88 -488);
FORCEPROP 2 LAST CDS_XR_PAGE_TITLE CR-184 : @T6G_MB_LIB.T6G(SCH_1):PAGE184
J 0
(-7990 4775);
DISPLAY 0.638298 (-7990 4775);
PAINT PINK (-7990 4775);
DISPLAY INVISIBLE (-7990 4775);
WIRE 16 -1 (-7800 4700)(-7800 4650);
WIRE 16 -1 (-7450 5275)(-7450 5150);
WIRE 16 -1 (-7800 1775)(-7800 1725);
WIRE 16 -1 (-7450 2350)(-7450 2225);
WIRE 16 -1 (-4575 775)(-4575 700);
WIRE 16 -1 (-4675 3700)(-4675 3625);
WIRE 16 -1 (-8100 5900)(-8100 5850);
WIRE 16 -1 (-8450 5900)(-8450 5850);
WIRE 16 -1 (-7850 1175)(-7850 1050);
WIRE 16 -1 (-7900 4100)(-7900 3975);
WIRE 16 -1 (-7300 1250)(-7525 1250);
WIRE 16 -1 (-7525 1250)(-7525 1125);
WIRE 16 -1 (-7325 4175)(-7550 4175);
WIRE 16 -1 (-7550 4175)(-7550 4050);
WIRE 16 -1 (-2425 3075)(-2750 3075);
WIRE 16 -1 (-2425 3075)(-2100 3075);
WIRE 16 -1 (-2425 3000)(-2425 3075);
WIRE 16 -1 (-2750 3075)(-2750 3100);
WIRE 16 -1 (-2750 3000)(-2750 3075);
WIRE 16 -1 (-2100 3075)(-2100 3000);
WIRE 16 -1 (-4600 1900)(-3875 1900);
FORCEPROP 2 LAST SIG_NAME SW_PVDD11_S3_P0_BOOT2_RC
J 2
(-3910 1910);
DISPLAY 0.489362 (-3910 1910);
FORCEPROP 2 LASTPROP $XRERR UNIQUE?
J 0
(-4150 1910);
DISPLAY 0.638298 (-4150 1910);
PAINT MONO (-4150 1910);
DISPLAY INVISIBLE (-4150 1910);
WIRE 16 -1 (-3875 1900)(-3875 1875);
WIRE 16 -1 (-4675 4825)(-3950 4825);
FORCEPROP 2 LAST SIG_NAME SW_PVDD11_S3_P0_BOOT1_RC
J 2
(-3985 4835);
DISPLAY 0.489362 (-3985 4835);
FORCEPROP 2 LASTPROP $XRERR UNIQUE?
J 0
(-4225 4835);
DISPLAY 0.638298 (-4225 4835);
PAINT MONO (-4225 4835);
DISPLAY INVISIBLE (-4225 4835);
WIRE 16 -1 (-3950 4825)(-3950 4800);
WIRE 16 -1 (-3950 4600)(-3950 4575);
WIRE 16 -1 (-3950 4575)(-5675 4575);
FORCEPROP 2 LAST SIG_NAME SW_PVDD11_S3_P0_PH1
J 0
(-5535 4585);
DISPLAY 0.489362 (-5535 4585);
FORCEPROP 2 LASTPROP $XRERR UNIQUE?
J 0
(-5775 4585);
DISPLAY 0.638298 (-5775 4585);
PAINT MONO (-5775 4585);
DISPLAY INVISIBLE (-5775 4585);
WIRE 16 -1 (-4675 4375)(-4675 4475);
WIRE 16 -1 (-4675 4475)(-3400 4475);
WIRE 16 -1 (-5675 4475)(-4675 4475);
FORCEPROP 2 LAST SIG_NAME SW_PVDD11_S3_P0_SW1
J 0
(-5535 4485);
DISPLAY 0.489362 (-5535 4485);
FORCEPROP 2 LASTPROP $XRERR UNIQUE?
J 0
(-5775 4485);
DISPLAY 0.638298 (-5775 4485);
PAINT MONO (-5775 4485);
DISPLAY INVISIBLE (-5775 4485);
WIRE 16 -1 (-3350 5275)(-3350 5150);
WIRE 16 -1 (-3750 5150)(-3350 5150);
WIRE 16 -1 (-3750 5275)(-3750 5150);
WIRE 16 -1 (-3925 5150)(-3750 5150);
WIRE 16 -1 (-3925 5150)(-3925 5100);
WIRE 16 -1 (-3925 5150)(-4100 5150);
WIRE 16 -1 (-4100 5275)(-4100 5150);
WIRE 16 -1 (-4400 5150)(-4100 5150);
WIRE 16 -1 (-4400 5275)(-4400 5150);
WIRE 16 -1 (-4400 5150)(-4775 5150);
WIRE 16 -1 (-4775 5275)(-4775 5150);
WIRE 16 -1 (-5075 5150)(-4775 5150);
WIRE 16 -1 (-5075 5275)(-5075 5150);
WIRE 16 -1 (-5400 5150)(-5075 5150);
WIRE 16 -1 (-5400 5275)(-5400 5150);
WIRE 16 -1 (-2525 5700)(-2525 5550);
WIRE 16 -1 (-2525 5550)(-2825 5550);
WIRE 16 -1 (-2575 4475)(-2575 3500);
WIRE 16 -1 (-2575 4475)(-2325 4475);
WIRE 16 -1 (-2575 4475)(-3200 4475);
WIRE 16 -1 (-2575 3500)(-3700 3500);
WIRE 16 -1 (-2325 4475)(-1975 4475);
WIRE 16 -1 (-2325 4400)(-2325 4475);
WIRE 16 -1 (-1975 4475)(-1550 4475);
WIRE 16 -1 (-1975 4475)(-1975 4400);
WIRE 16 -1 (-1225 4475)(-1550 4475);
WIRE 16 -1 (-1550 4475)(-1550 4400);
WIRE 16 -1 (-1225 4550)(-1225 4475);
WIRE 16 -1 (-1225 4475)(-1225 4375);
WIRE 16 -1 (-2325 4075)(-2325 4200);
WIRE 16 -1 (-2325 4075)(-1975 4075);
WIRE 16 -1 (-1975 4200)(-1975 4075);
WIRE 16 -1 (-1975 4075)(-1550 4075);
WIRE 16 -1 (-1550 4200)(-1550 4075);
WIRE 16 -1 (-1225 4075)(-1550 4075);
WIRE 16 -1 (-1225 4175)(-1225 4075);
WIRE 16 -1 (-1225 4025)(-1225 4075);
WIRE 16 -1 (-1700 3075)(-1375 3075);
WIRE 16 -1 (-1700 3075)(-1700 3100);
WIRE 16 -1 (-1700 3025)(-1700 3075);
WIRE 16 -1 (-1375 3025)(-1375 3075);
WIRE 16 -1 (-1375 3075)(-1075 3075);
WIRE 16 -1 (-1075 3075)(-725 3075);
WIRE 16 -1 (-1075 3075)(-1075 3025);
WIRE 16 -1 (-725 3075)(-725 3025);
WIRE 16 -1 (-1700 2700)(-1375 2700);
WIRE 16 -1 (-1700 2825)(-1700 2700);
WIRE 16 -1 (-1700 2700)(-1700 2650);
WIRE 16 -1 (-1075 2700)(-1375 2700);
WIRE 16 -1 (-1375 2825)(-1375 2700);
WIRE 16 -1 (-725 2700)(-1075 2700);
WIRE 16 -1 (-1075 2825)(-1075 2700);
WIRE 16 -1 (-725 2825)(-725 2700);
WIRE 16 -1 (-2400 1275)(-2400 1150);
WIRE 16 -1 (-1975 1150)(-2400 1150);
WIRE 16 -1 (-1975 1275)(-1975 1150);
WIRE 16 -1 (-1975 1075)(-1975 1150);
WIRE 16 -1 (-2750 2625)(-2750 2675);
WIRE 16 -1 (-2425 2675)(-2750 2675);
WIRE 16 -1 (-2750 2675)(-2750 2800);
WIRE 16 -1 (-2100 2675)(-2425 2675);
WIRE 16 -1 (-2425 2800)(-2425 2675);
WIRE 16 -1 (-2100 2800)(-2100 2675);
WIRE 16 -1 (-5625 1550)(-4575 1550);
FORCEPROP 2 LAST SIG_NAME SW_PVDD11_S3_P0_SW2
J 0
(-5485 1560);
DISPLAY 0.489362 (-5485 1560);
FORCEPROP 2 LASTPROP $XRERR UNIQUE?
J 0
(-5725 1560);
DISPLAY 0.638298 (-5725 1560);
PAINT MONO (-5725 1560);
DISPLAY INVISIBLE (-5725 1560);
WIRE 16 -1 (-4575 1550)(-3500 1550);
WIRE 16 -1 (-4575 1450)(-4575 1550);
WIRE 16 -1 (-5675 4825)(-4875 4825);
FORCEPROP 2 LAST SIG_NAME SW_PVDD11_S3_P0_BOOT1
J 0
(-5535 4835);
DISPLAY 0.489362 (-5535 4835);
FORCEPROP 2 LASTPROP $XRERR UNIQUE?
J 0
(-5775 4835);
DISPLAY 0.638298 (-5775 4835);
PAINT MONO (-5775 4835);
DISPLAY INVISIBLE (-5775 4835);
WIRE 16 -1 (-5675 4225)(-4925 4225);
WIRE 16 -1 (-4925 3500)(-4925 4225);
WIRE 16 -1 (-3900 3500)(-4925 3500);
FORCEPROP 2 LAST SIG_NAME PVDD11_S3_P0_VOS1
J 0
(-5535 4225);
DISPLAY 0.489362 (-5535 4225);
FORCEPROP 2 LASTPROP $XRERR UNIQUE?
J 0
(-5775 4225);
DISPLAY 0.638298 (-5775 4225);
PAINT MONO (-5775 4225);
DISPLAY INVISIBLE (-5775 4225);
WIRE 16 -1 (-5675 4125)(-5150 4125);
FORCEPROP 2 LAST SIG_NAME NC_PVDD11_S3_P0_GL2_1
J 0
(-5535 4135);
DISPLAY 0.489362 (-5535 4135);
FORCEPROP 2 LASTPROP $XRERR UNIQUE?
J 0
(-5120 4125);
DISPLAY 0.638298 (-5120 4125);
PAINT MONO (-5120 4125);
DISPLAY INVISIBLE (-5120 4125);
WIRE 16 -1 (-5675 4175)(-5150 4175);
FORCEPROP 2 LAST SIG_NAME NC_PVDD11_S3_P0_GL1_1
J 0
(-5535 4185);
DISPLAY 0.489362 (-5535 4185);
FORCEPROP 2 LASTPROP $XRERR UNIQUE?
J 0
(-5120 4175);
DISPLAY 0.638298 (-5120 4175);
PAINT MONO (-5120 4175);
DISPLAY INVISIBLE (-5120 4175);
WIRE 16 -1 (-7125 4175)(-6525 4175);
FORCEPROP 2 LAST SIG_NAME PVDD11_S3_P0_LSET1
J 2
(-6610 4185);
DISPLAY 0.489362 (-6610 4185);
FORCEPROP 2 LASTPROP $XRERR UNIQUE?
J 0
(-6850 4185);
DISPLAY 0.638298 (-6850 4185);
PAINT MONO (-6850 4185);
DISPLAY INVISIBLE (-6850 4185);
WIRE 16 -1 (-6525 4225)(-6975 4225);
FORCEPROP 2 LAST SIG_NAME NC_PVDD11_S3_P0_DNC1
J 2
(-6610 4235);
DISPLAY 0.489362 (-6610 4235);
FORCEPROP 2 LASTPROP $XRERR UNIQUE?
J 0
(-7215 4225);
DISPLAY 0.638298 (-7215 4225);
PAINT MONO (-7215 4225);
DISPLAY INVISIBLE (-7215 4225);
WIRE 16 -1 (-6525 4475)(-7175 4475);
FORCEPROP 2 LAST SIG_NAME PVDD11_S3_P0_IMON1
J 2
(-6610 4485);
DISPLAY 0.489362 (-6610 4485);
WIRE 16 -1 (-7025 4950)(-7800 4950);
WIRE 16 -1 (-7025 4950)(-7025 4825);
FORCEPROP 2 LAST SIG_NAME PVDD11_S3_P0_VCC1
J 2
(-6610 4835);
DISPLAY 0.489362 (-6610 4835);
FORCEPROP 2 LASTPROP $XRERR UNIQUE?
J 0
(-6850 4835);
DISPLAY 0.638298 (-6850 4835);
PAINT MONO (-6850 4835);
DISPLAY INVISIBLE (-6850 4835);
WIRE 16 -1 (-7800 5250)(-7800 4950);
WIRE 16 -1 (-7800 4950)(-7800 4900);
WIRE 16 -1 (-6525 4825)(-7025 4825);
WIRE 16 -1 (-7025 4825)(-7025 4625);
WIRE 16 -1 (-7025 4625)(-6525 4625);
WIRE 16 -1 (-8075 4375)(-7900 4375);
WIRE 16 -1 (-6525 4375)(-7900 4375);
FORCEPROP 2 LAST SIG_NAME PVDD11_S3_P0_VCCS
J 2
(-6610 4385);
DISPLAY 0.489362 (-6610 4385);
WIRE 16 -1 (-7900 4300)(-7900 4375);
WIRE 16 -1 (-4675 4175)(-4675 3900);
FORCEPROP 2 LAST SIG_NAME SW_PVDD11_S3_P0_SW1_RC
J 0
(-4635 4010);
DISPLAY 0.489362 (-4635 4010);
FORCEPROP 2 LASTPROP $XRERR UNIQUE?
J 0
(-4875 4010);
DISPLAY 0.638298 (-4875 4010);
PAINT MONO (-4875 4010);
DISPLAY INVISIBLE (-4875 4010);
WIRE 16 -1 (-5350 2350)(-5350 2225);
WIRE 16 -1 (-5350 2225)(-5025 2225);
WIRE 16 -1 (-5025 2225)(-4700 2225);
WIRE 16 -1 (-5025 2350)(-5025 2225);
WIRE 16 -1 (-4700 2225)(-4400 2225);
WIRE 16 -1 (-4700 2350)(-4700 2225);
WIRE 16 -1 (-4075 2225)(-4400 2225);
WIRE 16 -1 (-4400 2350)(-4400 2225);
WIRE 16 -1 (-3725 2225)(-4075 2225);
WIRE 16 -1 (-4075 2350)(-4075 2225);
WIRE 16 -1 (-3725 2350)(-3725 2225);
WIRE 16 -1 (-3725 2225)(-3725 2175);
WIRE 16 -1 (-5675 3875)(-5450 3875);
WIRE 16 -1 (-5450 3875)(-5450 3925);
WIRE 16 -1 (-5450 3800)(-5450 3875);
WIRE 16 -1 (-5675 3925)(-5450 3925);
WIRE 16 -1 (-5450 3975)(-5450 3925);
WIRE 16 -1 (-5675 3975)(-5450 3975);
WIRE 16 -1 (-5450 4025)(-5450 3975);
WIRE 16 -1 (-5450 4025)(-5675 4025);
WIRE 16 -1 (-5500 2200)(-5500 2150);
WIRE 16 -1 (-5625 2200)(-5500 2200);
WIRE 16 -1 (-5500 2625)(-5500 2200);
WIRE 16 -1 (-5500 2150)(-5625 2150);
WIRE 16 -1 (-5500 2625)(-5350 2625);
WIRE 16 -1 (-5350 2550)(-5350 2625);
WIRE 16 -1 (-5025 2625)(-5350 2625);
WIRE 16 -1 (-4700 2625)(-5025 2625);
WIRE 16 -1 (-5025 2550)(-5025 2625);
WIRE 16 -1 (-4700 2625)(-4400 2625);
WIRE 16 -1 (-4700 2625)(-4700 2550);
WIRE 16 -1 (-4075 2625)(-4400 2625);
WIRE 16 -1 (-4400 2625)(-4400 2550);
WIRE 16 -1 (-3725 2625)(-4075 2625);
WIRE 16 -1 (-4075 2550)(-4075 2625);
WIRE 16 -1 (-3725 2675)(-3725 2625);
WIRE 16 -1 (-3725 2550)(-3725 2625);
WIRE 16 -1 (-4575 1250)(-4575 975);
FORCEPROP 2 LAST SIG_NAME SW_PVDD11_S3_P0_SW2_RC
J 0
(-4535 1085);
DISPLAY 0.489362 (-4535 1085);
FORCEPROP 2 LASTPROP $XRERR UNIQUE?
J 0
(-4775 1085);
DISPLAY 0.638298 (-4775 1085);
PAINT MONO (-4775 1085);
DISPLAY INVISIBLE (-4775 1085);
WIRE 16 -1 (-5625 1900)(-4800 1900);
FORCEPROP 2 LAST SIG_NAME SW_PVDD11_S3_P0_BOOT2
J 0
(-5485 1910);
DISPLAY 0.489362 (-5485 1910);
FORCEPROP 2 LASTPROP $XRERR UNIQUE?
J 0
(-5725 1910);
DISPLAY 0.638298 (-5725 1910);
PAINT MONO (-5725 1910);
DISPLAY INVISIBLE (-5725 1910);
WIRE 16 -1 (-5625 1250)(-5100 1250);
FORCEPROP 2 LAST SIG_NAME NC_PVDD11_S3_P0_GL1_2
J 0
(-5485 1260);
DISPLAY 0.489362 (-5485 1260);
FORCEPROP 2 LASTPROP $XRERR UNIQUE?
J 0
(-5070 1250);
DISPLAY 0.638298 (-5070 1250);
PAINT MONO (-5070 1250);
DISPLAY INVISIBLE (-5070 1250);
WIRE 16 -1 (-5625 1200)(-5100 1200);
FORCEPROP 2 LAST SIG_NAME NC_PVDD11_S3_P0_GL2_2
J 0
(-5485 1210);
DISPLAY 0.489362 (-5485 1210);
FORCEPROP 2 LASTPROP $XRERR UNIQUE?
J 0
(-5070 1200);
DISPLAY 0.638298 (-5070 1200);
PAINT MONO (-5070 1200);
DISPLAY INVISIBLE (-5070 1200);
WIRE 16 -1 (-5625 950)(-5450 950);
WIRE 16 -1 (-5450 950)(-5450 1000);
WIRE 16 -1 (-5450 875)(-5450 950);
WIRE 16 -1 (-5625 1000)(-5450 1000);
WIRE 16 -1 (-5450 1000)(-5450 1050);
WIRE 16 -1 (-5450 1100)(-5450 1050);
WIRE 16 -1 (-5625 1050)(-5450 1050);
WIRE 16 -1 (-5450 1100)(-5625 1100);
WIRE 16 -1 (-6525 3975)(-7150 3975);
FORCEPROP 2 LAST SIG_NAME PVDD11_S3_P0_TEMP0
J 2
(-6610 3985);
DISPLAY 0.489362 (-6610 3985);
WIRE 16 -1 (-6525 3875)(-7125 3875);
FORCEPROP 2 LAST SIG_NAME PVDD11_S3_P0_PWM1
J 2
(-6610 3885);
DISPLAY 0.489362 (-6610 3885);
WIRE 16 -1 (-7800 2525)(-7800 2650);
WIRE 16 -1 (-7450 2650)(-7800 2650);
WIRE 16 -1 (-7800 2800)(-7800 2650);
WIRE 16 -1 (-6850 2650)(-7450 2650);
WIRE 16 -1 (-7450 2550)(-7450 2650);
WIRE 16 -1 (-6850 2200)(-6850 2650);
WIRE 16 -1 (-6850 2200)(-6475 2200);
WIRE 16 -1 (-6475 1550)(-7125 1550);
FORCEPROP 2 LAST SIG_NAME PVDD11_S3_P0_IMON2
J 2
(-6560 1560);
DISPLAY 0.489362 (-6560 1560);
WIRE 16 -1 (-6475 1050)(-7100 1050);
FORCEPROP 2 LAST SIG_NAME PVDD11_S3_P0_TEMP0
J 2
(-6560 1060);
DISPLAY 0.489362 (-6560 1060);
WIRE 16 -1 (-7100 1250)(-6475 1250);
FORCEPROP 2 LAST SIG_NAME PVDD11_S3_P0_LSET2
J 2
(-6560 1260);
DISPLAY 0.489362 (-6560 1260);
FORCEPROP 2 LASTPROP $XRERR UNIQUE?
J 0
(-6800 1260);
DISPLAY 0.638298 (-6800 1260);
PAINT MONO (-6800 1260);
DISPLAY INVISIBLE (-6800 1260);
WIRE 16 -1 (-6475 1300)(-6925 1300);
FORCEPROP 2 LAST SIG_NAME NC_PVDD11_S3_P0_DNC2
J 2
(-6560 1310);
DISPLAY 0.489362 (-6560 1310);
FORCEPROP 2 LASTPROP $XRERR UNIQUE?
J 0
(-7165 1300);
DISPLAY 0.638298 (-7165 1300);
PAINT MONO (-7165 1300);
DISPLAY INVISIBLE (-7165 1300);
WIRE 16 -1 (-6475 950)(-7075 950);
FORCEPROP 2 LAST SIG_NAME PVDD11_S3_P0_PWM2
J 2
(-6560 960);
DISPLAY 0.489362 (-6560 960);
WIRE 16 -1 (-8025 1450)(-7850 1450);
WIRE 16 -1 (-6475 1450)(-7850 1450);
FORCEPROP 2 LAST SIG_NAME PVDD11_S3_P0_VCCS
J 2
(-6560 1460);
DISPLAY 0.489362 (-6560 1460);
WIRE 16 -1 (-7850 1375)(-7850 1450);
WIRE 16 -1 (-8450 5650)(-8450 5575);
WIRE 16 -1 (-8100 5575)(-8450 5575);
WIRE 16 -1 (-8100 5650)(-8100 5575);
WIRE 16 -1 (-7800 5575)(-8100 5575);
WIRE 16 -1 (-7600 5575)(-7800 5575);
WIRE 16 -1 (-7800 5450)(-7800 5575);
WIRE 16 -1 (-7600 5900)(-7600 5575);
WIRE 16 -1 (-7600 5575)(-7450 5575);
WIRE 16 -1 (-6875 5575)(-7450 5575);
WIRE 16 -1 (-7450 5475)(-7450 5575);
WIRE 16 -1 (-6875 5125)(-6875 5575);
WIRE 16 -1 (-6875 5125)(-6525 5125);
WIRE 16 -1 (-3350 5475)(-3350 5550);
WIRE 16 -1 (-3025 5550)(-3350 5550);
WIRE 16 -1 (-3350 5550)(-3750 5550);
WIRE 16 -1 (-3750 5475)(-3750 5550);
WIRE 16 -1 (-3925 5550)(-3750 5550);
WIRE 16 -1 (-3925 5675)(-3925 5550);
WIRE 16 -1 (-3925 5550)(-4100 5550);
WIRE 16 -1 (-4100 5550)(-4100 5475);
WIRE 16 -1 (-4400 5550)(-4100 5550);
WIRE 16 -1 (-4400 5550)(-4400 5475);
WIRE 16 -1 (-4400 5550)(-4775 5550);
WIRE 16 -1 (-4775 5475)(-4775 5550);
WIRE 16 -1 (-5075 5550)(-4775 5550);
WIRE 16 -1 (-5075 5475)(-5075 5550);
WIRE 16 -1 (-5400 5550)(-5075 5550);
WIRE 16 -1 (-5400 5475)(-5400 5550);
WIRE 16 -1 (-5575 5550)(-5400 5550);
WIRE 16 -1 (-5575 5550)(-5575 5125);
WIRE 16 -1 (-5575 5125)(-5575 5075);
WIRE 16 -1 (-5675 5125)(-5575 5125);
WIRE 16 -1 (-5575 5075)(-5675 5075);
WIRE 17 273 (-3050 2450)(-350 2450);
WIRE 17 273 (-3050 2450)(-3050 3375);
WIRE 17 273 (-350 3375)(-350 2450);
WIRE 17 273 (-3050 3375)(-350 3375);
WIRE 16 -1 (-2650 1550)(-2650 600);
WIRE 16 -1 (-2650 1550)(-2400 1550);
WIRE 16 -1 (-2650 1550)(-3300 1550);
WIRE 16 -1 (-2650 600)(-3375 600);
WIRE 16 -1 (-2400 1550)(-1975 1550);
WIRE 16 -1 (-2400 1550)(-2400 1475);
WIRE 16 -1 (-1975 1650)(-1975 1550);
WIRE 16 -1 (-1975 1550)(-1975 1475);
WIRE 16 -1 (-3875 1675)(-3875 1650);
WIRE 16 -1 (-3875 1650)(-5625 1650);
FORCEPROP 2 LAST SIG_NAME SW_PVDD11_S3_P0_PH2
J 0
(-5485 1660);
DISPLAY 0.489362 (-5485 1660);
FORCEPROP 2 LASTPROP $XRERR UNIQUE?
J 0
(-5725 1660);
DISPLAY 0.638298 (-5725 1660);
PAINT MONO (-5725 1660);
DISPLAY INVISIBLE (-5725 1660);
WIRE 16 -1 (-5625 1300)(-4875 1300);
WIRE 16 -1 (-4875 600)(-4875 1300);
WIRE 16 -1 (-3575 600)(-4875 600);
FORCEPROP 2 LAST SIG_NAME PVDD11_S3_P0_VOS2
J 0
(-5485 1325);
DISPLAY 0.489362 (-5485 1325);
FORCEPROP 2 LASTPROP $XRERR UNIQUE?
J 0
(-5725 1325);
DISPLAY 0.638298 (-5725 1325);
PAINT MONO (-5725 1325);
DISPLAY INVISIBLE (-5725 1325);
WIRE 16 -1 (-7025 1700)(-6475 1700);
WIRE 16 -1 (-7025 1900)(-7025 1700);
WIRE 16 -1 (-7025 2050)(-7025 1900);
FORCEPROP 2 LAST SIG_NAME PVDD11_S3_P0_VCC2
J 2
(-6585 1910);
DISPLAY 0.489362 (-6585 1910);
FORCEPROP 2 LASTPROP $XRERR UNIQUE?
J 0
(-6825 1910);
DISPLAY 0.638298 (-6825 1910);
PAINT MONO (-6825 1910);
DISPLAY INVISIBLE (-6825 1910);
WIRE 16 -1 (-6475 1900)(-7025 1900);
WIRE 16 -1 (-7025 2050)(-7800 2050);
WIRE 16 -1 (-7800 2325)(-7800 2050);
WIRE 16 -1 (-7800 2050)(-7800 1975);
DOT 1 (-3925 5550);
DOT 1 (-5025 2225);
DOT 1 (-4075 2225);
DOT 1 (-3725 2225);
DOT 1 (-3725 2625);
DOT 1 (-4100 5550);
DOT 1 (-7850 1450);
DOT 1 (-7025 1900);
DOT 1 (-7800 2050);
DOT 1 (-7800 2650);
DOT 1 (-7450 2650);
DOT 1 (-5450 950);
DOT 1 (-5450 1000);
DOT 1 (-5450 1050);
DOT 1 (-4575 1550);
DOT 1 (-5500 2200);
DOT 1 (-5350 2625);
DOT 1 (-5450 3925);
DOT 1 (-5450 3875);
DOT 1 (-5450 3975);
DOT 1 (-4700 2225);
DOT 1 (-5025 2625);
DOT 1 (-4700 2625);
DOT 1 (-4400 2225);
DOT 1 (-4400 2625);
DOT 1 (-7900 4375);
DOT 1 (-7800 4950);
DOT 1 (-8100 5575);
DOT 1 (-7800 5575);
DOT 1 (-7600 5575);
DOT 1 (-7450 5575);
DOT 1 (-7025 4825);
DOT 1 (-5575 5125);
DOT 1 (-5400 5550);
DOT 1 (-5075 5150);
DOT 1 (-5075 5550);
DOT 1 (-4775 5150);
DOT 1 (-4400 5550);
DOT 1 (-4100 5150);
DOT 1 (-2650 1550);
DOT 1 (-2400 1550);
DOT 1 (-4075 2625);
DOT 1 (-1975 1150);
DOT 1 (-1550 4075);
DOT 1 (-1975 4075);
DOT 1 (-1225 4075);
DOT 1 (-3750 5150);
DOT 1 (-2575 4475);
DOT 1 (-2325 4475);
DOT 1 (-1975 4475);
DOT 1 (-1550 4475);
DOT 1 (-1225 4475);
DOT 1 (-1975 1550);
DOT 1 (-2425 3075);
DOT 1 (-2425 2675);
DOT 1 (-2750 3075);
DOT 1 (-2750 2675);
DOT 1 (-1375 3075);
DOT 1 (-1375 2700);
DOT 1 (-1075 3075);
DOT 1 (-1075 2700);
DOT 1 (-1700 2700);
DOT 1 (-1700 3075);
DOT 1 (-4400 5150);
DOT 1 (-3350 5550);
DOT 1 (-3750 5550);
DOT 1 (-3925 5150);
DOT 1 (-4775 5550);
DOT 1 (-4675 4475);
FORCENOTE
PR133,PR134,PR135,PR136 = CS00002JB38
(-9325 325) 0;
DISPLAY LEFT (-9325 325);
DISPLAY 1.021277 (-9325 325);
PAINT WHITE (-9325 325);
FORCENOTE
PR137,PR138 = EMPTY
(-9325 250) 0;
DISPLAY LEFT (-9325 250);
DISPLAY 1.021277 (-9325 250);
PAINT WHITE (-9325 250);
FORCENOTE
PC201_1,PC202_2 = EMPTY
(-9325 175) 0;
DISPLAY LEFT (-9325 175);
DISPLAY 1.021277 (-9325 175);
PAINT WHITE (-9325 175);
FORCENOTE
3RD SOURCE:MPS BOM
(-9325 50) 0;
DISPLAY LEFT (-9325 50);
DISPLAY 1.021277 (-9325 50);
PAINT WHITE (-9325 50);
FORCENOTE
PU22,PU23=AL087000A02
(-9325 -25) 0;
DISPLAY LEFT (-9325 -25);
DISPLAY 1.021277 (-9325 -25);
PAINT WHITE (-9325 -25);
FORCENOTE
PU22,PU23 = AL021590000/TDA21590
(-9325 400) 0;
DISPLAY LEFT (-9325 400);
DISPLAY 1.021277 (-9325 400);
PAINT WHITE (-9325 400);
FORCENOTE
2ND SOURCE:INFENEON BOM
(-9325 475) 0;
DISPLAY LEFT (-9325 475);
DISPLAY 1.021277 (-9325 475);
PAINT WHITE (-9325 475);
FORCENOTE
BOM NOTE
(-9325 875) 0;
DISPLAY LEFT (-9325 875);
DISPLAY 1.021277 (-9325 875);
PAINT WHITE (-9325 875);
FORCENOTE
MAIN SOURCE:RENESAS BOM
(-9325 750) 0;
DISPLAY LEFT (-9325 750);
DISPLAY 1.021277 (-9325 750);
PAINT WHITE (-9325 750);
FORCENOTE
PU22,PU23=AL099390004/ISL99390FRZ-TR5935
(-9325 675) 0;
DISPLAY LEFT (-9325 675);
DISPLAY 1.021277 (-9325 675);
PAINT WHITE (-9325 675);
FORCENOTE
3RD=CC7390JMZ13
(-1525 2500) 0;
DISPLAY LEFT (-1525 2500);
DISPLAY 0.638298 (-1525 2500);
PAINT WHITE (-1525 2500);
FORCENOTE
2ND=CC7390JMZ11
(-1525 2550) 0;
DISPLAY LEFT (-1525 2550);
DISPLAY 0.638298 (-1525 2550);
PAINT WHITE (-1525 2550);
FORCENOTE
2ND=CH747LM8822
(-2675 2500) 0;
DISPLAY LEFT (-2675 2500);
DISPLAY 0.638298 (-2675 2500);
PAINT WHITE (-2675 2500);
FORCENOTE
7.3*4.3*1.9
(-2675 2550) 0;
DISPLAY LEFT (-2675 2550);
DISPLAY 0.638298 (-2675 2550);
PAINT WHITE (-2675 2550);
FORCENOTE
3RD=CC72204MD03
(-3450 4900) 0;
DISPLAY LEFT (-3450 4900);
DISPLAY 0.638298 (-3450 4900);
PAINT WHITE (-3450 4900);
FORCENOTE
2ND=CC72204MD01
(-3450 4950) 0;
DISPLAY LEFT (-3450 4950);
DISPLAY 0.638298 (-3450 4950);
PAINT WHITE (-3450 4950);
FORCENOTE
8*11.5
(-3450 5000) 0;
DISPLAY LEFT (-3450 5000);
DISPLAY 0.638298 (-3450 5000);
PAINT WHITE (-3450 5000);
FORCENOTE
IRIPPLE:4.65A
(-3450 5050) 0;
DISPLAY LEFT (-3450 5050);
DISPLAY 0.638298 (-3450 5050);
PAINT WHITE (-3450 5050);
FORCENOTE
ESR=16M OHM
(-3450 5100) 0;
DISPLAY LEFT (-3450 5100);
DISPLAY 0.638298 (-3450 5100);
PAINT WHITE (-3450 5100);
FORCENOTE
PVDD11_S3_P0_PHASE1
(-6650 5875) 0;
DISPLAY LEFT (-6650 5875);
DISPLAY 1.595745 (-6650 5875);
PAINT WHITE (-6650 5875);
FORCENOTE
PG2289.101HLT
(-3000 5475) 0;
DISPLAY LEFT (-3000 5475);
DISPLAY 0.638298 (-3000 5475);
PAINT WHITE (-3000 5475);
FORCENOTE
ISAT:13A@100C
(-3000 5425) 0;
DISPLAY LEFT (-3000 5425);
DISPLAY 0.638298 (-3000 5425);
PAINT WHITE (-3000 5425);
FORCENOTE
4.5*4.7*4.5
(-3000 5375) 0;
DISPLAY LEFT (-3000 5375);
DISPLAY 0.638298 (-3000 5375);
PAINT WHITE (-3000 5375);
FORCENOTE
DCR=0.125M OHM
(-3375 4050) 0;
DISPLAY LEFT (-3375 4050);
DISPLAY 0.638298 (-3375 4050);
PAINT WHITE (-3375 4050);
FORCENOTE
ISAT:88A@100C
(-3375 4150) 0;
DISPLAY LEFT (-3375 4150);
DISPLAY 0.638298 (-3375 4150);
PAINT WHITE (-3375 4150);
FORCENOTE
2ND=CV+12^0TZ02
(-3375 4000) 0;
DISPLAY LEFT (-3375 4000);
DISPLAY 0.638298 (-3375 4000);
PAINT WHITE (-3375 4000);
FORCENOTE
3RD=CV+12^0TZ01
(-3375 3950) 0;
DISPLAY LEFT (-3375 3950);
DISPLAY 0.638298 (-3375 3950);
PAINT WHITE (-3375 3950);
FORCENOTE
PGL6054.121AHLT
(-3500 1300) 0;
DISPLAY LEFT (-3500 1300);
DISPLAY 0.638298 (-3500 1300);
PAINT WHITE (-3500 1300);
FORCENOTE
10.0*6.0*12.0
(-3500 1200) 0;
DISPLAY LEFT (-3500 1200);
DISPLAY 0.638298 (-3500 1200);
PAINT WHITE (-3500 1200);
FORCENOTE
DCR=0.125M OHM
(-3500 1150) 0;
DISPLAY LEFT (-3500 1150);
DISPLAY 0.638298 (-3500 1150);
PAINT WHITE (-3500 1150);
FORCENOTE
2ND=CV+12^0TZ02
(-3500 1100) 0;
DISPLAY LEFT (-3500 1100);
DISPLAY 0.638298 (-3500 1100);
PAINT WHITE (-3500 1100);
FORCENOTE
3RD=CV+12^0TZ01
(-3500 1050) 0;
DISPLAY LEFT (-3500 1050);
DISPLAY 0.638298 (-3500 1050);
PAINT WHITE (-3500 1050);
FORCENOTE
ISAT:88A@100C
(-3500 1250) 0;
DISPLAY LEFT (-3500 1250);
DISPLAY 0.638298 (-3500 1250);
PAINT WHITE (-3500 1250);
FORCENOTE
PVDD11_S3_P0_PHASE2
(-6600 2950) 0;
DISPLAY LEFT (-6600 2950);
DISPLAY 1.595745 (-6600 2950);
PAINT WHITE (-6600 2950);
FORCENOTE
10.0*6.0*12.0
(-3375 4100) 0;
DISPLAY LEFT (-3375 4100);
DISPLAY 0.638298 (-3375 4100);
PAINT WHITE (-3375 4100);
FORCENOTE
PGL6054.121AHLT
(-3375 4200) 0;
DISPLAY LEFT (-3375 4200);
DISPLAY 0.638298 (-3375 4200);
PAINT WHITE (-3375 4200);
FORCENOTE
DCR:0.105M OHM
(-3000 5325) 0;
DISPLAY LEFT (-3000 5325);
DISPLAY 0.638298 (-3000 5325);
PAINT WHITE (-3000 5325);
FORCENOTE
2ND=CV+10G0MZ04
(-3000 5275) 0;
DISPLAY LEFT (-3000 5275);
DISPLAY 0.638298 (-3000 5275);
PAINT WHITE (-3000 5275);
FORCENOTE
3RD=CV+10G0MZ08
(-3000 5225) 0;
DISPLAY LEFT (-3000 5225);
DISPLAY 0.638298 (-3000 5225);
PAINT WHITE (-3000 5225);
FORCENOTE
PR413,PR135,PR136=CS00002JB38
(-9325 -100) 0;
DISPLAY LEFT (-9325 -100);
DISPLAY 1.021277 (-9325 -100);
PAINT WHITE (-9325 -100);
FORCENOTE
PR411,PC201_1,202_2,PR137,PR138=EMPTY
(-9325 -175) 0;
DISPLAY LEFT (-9325 -175);
DISPLAY 1.021277 (-9325 -175);
PAINT WHITE (-9325 -175);
FORCENOTE
ESR=10M OHM
(-1525 2650) 0;
DISPLAY LEFT (-1525 2650);
DISPLAY 0.638298 (-1525 2650);
PAINT WHITE (-1525 2650);
FORCENOTE
ESR=9M OHM
(-2675 2600) 0;
DISPLAY LEFT (-2675 2600);
DISPLAY 0.638298 (-2675 2600);
PAINT WHITE (-2675 2600);
FORCENOTE
5.0*5.8
(-1525 2600) 0;
DISPLAY LEFT (-1525 2600);
DISPLAY 0.638298 (-1525 2600);
PAINT WHITE (-1525 2600);
QUIT
